(kicad_sch
	(version 20250114)
	(generator "eeschema")
	(generator_version "9.0")
	(paper "A3")
	(title_block
		(title "CM4 Baseboard")
		(date "2026-01-05")
		(rev "1.1.1")
		(company "Antmicro Ltd")
		(comment 1 "www.antmicro.com")
	)
	(text "Ethernet Connector"
		(exclude_from_sim no)
		(at 171.45 21.59 0)
		(effects
			(font
				(size 4 4)
				(thickness 0.5994)
				(bold yes)
			)
			(justify left bottom)
		)
	)
	(text "1/5.7 divider"
		(exclude_from_sim no)
		(at 280.67 180.975 0)
		(effects
			(font
				(size 1.27 1.27)
			)
			(justify left bottom)
		)
	)
	(text "Max power: 40W\n"
		(exclude_from_sim no)
		(at 124.46 203.2 0)
		(effects
			(font
				(size 1.27 1.27)
			)
			(justify left bottom)
		)
	)
	(text "Power over Ethernet"
		(exclude_from_sim no)
		(at 168.91 143.51 0)
		(effects
			(font
				(size 4 4)
				(thickness 0.5994)
				(bold yes)
			)
			(justify left bottom)
		)
	)
	(junction
		(at 185.42 182.88)
		(diameter 0)
		(color 0 0 0 0)
	)
	(junction
		(at 340.36 198.12)
		(diameter 0)
		(color 0 0 0 0)
	)
	(junction
		(at 349.25 198.12)
		(diameter 0)
		(color 0 0 0 0)
	)
	(junction
		(at 179.07 226.06)
		(diameter 0)
		(color 0 0 0 0)
	)
	(junction
		(at 231.14 182.88)
		(diameter 0)
		(color 0 0 0 0)
	)
	(junction
		(at 181.61 76.2)
		(diameter 0)
		(color 0 0 0 0)
	)
	(junction
		(at 224.79 182.88)
		(diameter 0)
		(color 0 0 0 0)
	)
	(junction
		(at 140.97 213.36)
		(diameter 0)
		(color 0 0 0 0)
	)
	(junction
		(at 247.65 182.88)
		(diameter 0)
		(color 0 0 0 0)
	)
	(junction
		(at 88.9 182.88)
		(diameter 0)
		(color 0 0 0 0)
	)
	(junction
		(at 217.17 182.88)
		(diameter 0)
		(color 0 0 0 0)
	)
	(junction
		(at 118.11 213.36)
		(diameter 0)
		(color 0 0 0 0)
	)
	(junction
		(at 367.03 198.12)
		(diameter 0)
		(color 0 0 0 0)
	)
	(junction
		(at 266.7 207.01)
		(diameter 0)
		(color 0 0 0 0)
	)
	(junction
		(at 358.14 182.88)
		(diameter 0)
		(color 0 0 0 0)
	)
	(junction
		(at 300.99 182.88)
		(diameter 0)
		(color 0 0 0 0)
	)
	(junction
		(at 151.13 39.37)
		(diameter 0)
		(color 0 0 0 0)
	)
	(junction
		(at 331.47 198.12)
		(diameter 0)
		(color 0 0 0 0)
	)
	(junction
		(at 153.67 210.82)
		(diameter 0)
		(color 0 0 0 0)
	)
	(junction
		(at 367.03 182.88)
		(diameter 0)
		(color 0 0 0 0)
	)
	(junction
		(at 358.14 198.12)
		(diameter 0)
		(color 0 0 0 0)
	)
	(junction
		(at 113.03 182.88)
		(diameter 0)
		(color 0 0 0 0)
	)
	(junction
		(at 328.93 198.12)
		(diameter 0)
		(color 0 0 0 0)
	)
	(junction
		(at 149.86 182.88)
		(diameter 0)
		(color 0 0 0 0)
	)
	(junction
		(at 328.93 182.88)
		(diameter 0)
		(color 0 0 0 0)
	)
	(junction
		(at 349.25 182.88)
		(diameter 0)
		(color 0 0 0 0)
	)
	(junction
		(at 143.51 213.36)
		(diameter 0)
		(color 0 0 0 0)
	)
	(junction
		(at 209.55 86.36)
		(diameter 0)
		(color 0 0 0 0)
	)
	(junction
		(at 128.27 215.9)
		(diameter 0)
		(color 0 0 0 0)
	)
	(junction
		(at 266.7 194.31)
		(diameter 0)
		(color 0 0 0 0)
	)
	(junction
		(at 128.27 218.44)
		(diameter 0)
		(color 0 0 0 0)
	)
	(junction
		(at 128.27 213.36)
		(diameter 0)
		(color 0 0 0 0)
	)
	(junction
		(at 153.67 182.88)
		(diameter 0)
		(color 0 0 0 0)
	)
	(junction
		(at 153.67 213.36)
		(diameter 0)
		(color 0 0 0 0)
	)
	(junction
		(at 195.58 182.88)
		(diameter 0)
		(color 0 0 0 0)
	)
	(junction
		(at 137.16 182.88)
		(diameter 0)
		(color 0 0 0 0)
	)
	(junction
		(at 68.58 203.2)
		(diameter 0)
		(color 0 0 0 0)
	)
	(junction
		(at 204.47 182.88)
		(diameter 0)
		(color 0 0 0 0)
	)
	(junction
		(at 208.28 73.66)
		(diameter 0)
		(color 0 0 0 0)
	)
	(junction
		(at 266.7 182.88)
		(diameter 0)
		(color 0 0 0 0)
	)
	(junction
		(at 331.47 182.88)
		(diameter 0)
		(color 0 0 0 0)
	)
	(junction
		(at 118.11 182.88)
		(diameter 0)
		(color 0 0 0 0)
	)
	(junction
		(at 238.76 182.88)
		(diameter 0)
		(color 0 0 0 0)
	)
	(junction
		(at 113.03 213.36)
		(diameter 0)
		(color 0 0 0 0)
	)
	(junction
		(at 340.36 182.88)
		(diameter 0)
		(color 0 0 0 0)
	)
	(junction
		(at 331.47 190.5)
		(diameter 0)
		(color 0 0 0 0)
	)
	(junction
		(at 287.02 194.31)
		(diameter 0)
		(color 0 0 0 0)
	)
	(junction
		(at 275.59 194.31)
		(diameter 0)
		(color 0 0 0 0)
	)
	(junction
		(at 287.02 182.88)
		(diameter 0)
		(color 0 0 0 0)
	)
	(no_connect
		(at 176.53 218.44)
	)
	(no_connect
		(at 154.94 226.06)
	)
	(bus_entry
		(at 246.38 78.74)
		(size -2.54 2.54)
		(stroke
			(width 0)
			(type default)
		)
	)
	(bus_entry
		(at 151.13 60.96)
		(size 2.54 2.54)
		(stroke
			(width 0)
			(type default)
		)
	)
	(bus_entry
		(at 151.13 55.88)
		(size 2.54 2.54)
		(stroke
			(width 0)
			(type default)
		)
	)
	(bus_entry
		(at 151.13 60.96)
		(size 2.54 2.54)
		(stroke
			(width 0)
			(type default)
		)
	)
	(bus_entry
		(at 151.13 48.26)
		(size 2.54 2.54)
		(stroke
			(width 0)
			(type default)
		)
	)
	(bus_entry
		(at 151.13 55.88)
		(size 2.54 2.54)
		(stroke
			(width 0)
			(type default)
		)
	)
	(bus_entry
		(at 151.13 50.8)
		(size 2.54 2.54)
		(stroke
			(width 0)
			(type default)
		)
	)
	(bus_entry
		(at 246.38 73.66)
		(size -2.54 2.54)
		(stroke
			(width 0)
			(type default)
		)
	)
	(bus_entry
		(at 151.13 58.42)
		(size 2.54 2.54)
		(stroke
			(width 0)
			(type default)
		)
	)
	(bus_entry
		(at 151.13 53.34)
		(size 2.54 2.54)
		(stroke
			(width 0)
			(type default)
		)
	)
	(bus_entry
		(at 151.13 50.8)
		(size 2.54 2.54)
		(stroke
			(width 0)
			(type default)
		)
	)
	(bus_entry
		(at 151.13 66.04)
		(size 2.54 2.54)
		(stroke
			(width 0)
			(type default)
		)
	)
	(bus_entry
		(at 151.13 58.42)
		(size 2.54 2.54)
		(stroke
			(width 0)
			(type default)
		)
	)
	(bus_entry
		(at 151.13 63.5)
		(size 2.54 2.54)
		(stroke
			(width 0)
			(type default)
		)
	)
	(bus_entry
		(at 151.13 63.5)
		(size 2.54 2.54)
		(stroke
			(width 0)
			(type default)
		)
	)
	(bus_entry
		(at 151.13 66.04)
		(size 2.54 2.54)
		(stroke
			(width 0)
			(type default)
		)
	)
	(bus_entry
		(at 151.13 53.34)
		(size 2.54 2.54)
		(stroke
			(width 0)
			(type default)
		)
	)
	(bus_entry
		(at 151.13 48.26)
		(size 2.54 2.54)
		(stroke
			(width 0)
			(type default)
		)
	)
	(bus
		(pts
			(xy 246.38 39.37) (xy 246.38 73.66)
		)
		(stroke
			(width 0)
			(type default)
		)
	)
	(wire
		(pts
			(xy 299.72 214.63) (xy 299.72 217.17)
		)
		(stroke
			(width 0)
			(type default)
		)
	)
	(wire
		(pts
			(xy 238.76 182.88) (xy 247.65 182.88)
		)
		(stroke
			(width 0)
			(type default)
		)
	)
	(wire
		(pts
			(xy 209.55 86.36) (xy 218.44 86.36)
		)
		(stroke
			(width 0)
			(type default)
		)
	)
	(wire
		(pts
			(xy 208.28 71.12) (xy 208.28 73.66)
		)
		(stroke
			(width 0)
			(type default)
		)
	)
	(wire
		(pts
			(xy 209.55 86.36) (xy 209.55 88.9)
		)
		(stroke
			(width 0)
			(type default)
		)
	)
	(wire
		(pts
			(xy 279.4 236.22) (xy 278.13 236.22)
		)
		(stroke
			(width 0)
			(type default)
		)
	)
	(wire
		(pts
			(xy 340.36 198.12) (xy 349.25 198.12)
		)
		(stroke
			(width 0)
			(type default)
		)
	)
	(wire
		(pts
			(xy 195.58 189.23) (xy 195.58 195.58)
		)
		(stroke
			(width 0)
			(type default)
		)
	)
	(wire
		(pts
			(xy 302.26 194.31) (xy 302.26 190.5)
		)
		(stroke
			(width 0)
			(type default)
		)
	)
	(wire
		(pts
			(xy 149.86 182.88) (xy 153.67 182.88)
		)
		(stroke
			(width 0)
			(type default)
		)
	)
	(wire
		(pts
			(xy 331.47 198.12) (xy 340.36 198.12)
		)
		(stroke
			(width 0)
			(type default)
		)
	)
	(bus
		(pts
			(xy 246.38 73.66) (xy 246.38 78.74)
		)
		(stroke
			(width 0)
			(type default)
		)
	)
	(wire
		(pts
			(xy 247.65 198.12) (xy 247.65 201.93)
		)
		(stroke
			(width 0)
			(type default)
		)
	)
	(wire
		(pts
			(xy 68.58 182.88) (xy 68.58 203.2)
		)
		(stroke
			(width 0)
			(type default)
		)
	)
	(wire
		(pts
			(xy 140.97 213.36) (xy 143.51 213.36)
		)
		(stroke
			(width 0)
			(type default)
		)
	)
	(wire
		(pts
			(xy 181.61 76.2) (xy 181.61 88.9)
		)
		(stroke
			(width 0)
			(type default)
		)
	)
	(wire
		(pts
			(xy 88.9 203.2) (xy 87.63 203.2)
		)
		(stroke
			(width 0)
			(type default)
		)
	)
	(wire
		(pts
			(xy 367.03 193.04) (xy 367.03 198.12)
		)
		(stroke
			(width 0)
			(type default)
		)
	)
	(wire
		(pts
			(xy 304.8 198.12) (xy 304.8 200.66)
		)
		(stroke
			(width 0)
			(type default)
		)
	)
	(wire
		(pts
			(xy 224.79 182.88) (xy 231.14 182.88)
		)
		(stroke
			(width 0)
			(type default)
		)
	)
	(wire
		(pts
			(xy 340.36 182.88) (xy 340.36 187.96)
		)
		(stroke
			(width 0)
			(type default)
		)
	)
	(wire
		(pts
			(xy 300.99 181.61) (xy 300.99 182.88)
		)
		(stroke
			(width 0)
			(type default)
		)
	)
	(wire
		(pts
			(xy 102.87 213.36) (xy 113.03 213.36)
		)
		(stroke
			(width 0)
			(type default)
		)
	)
	(wire
		(pts
			(xy 128.27 220.98) (xy 128.27 218.44)
		)
		(stroke
			(width 0)
			(type default)
		)
	)
	(wire
		(pts
			(xy 143.51 203.2) (xy 154.94 203.2)
		)
		(stroke
			(width 0)
			(type default)
		)
	)
	(bus
		(pts
			(xy 151.13 53.34) (xy 151.13 55.88)
		)
		(stroke
			(width 0)
			(type default)
		)
	)
	(wire
		(pts
			(xy 340.36 182.88) (xy 349.25 182.88)
		)
		(stroke
			(width 0)
			(type default)
		)
	)
	(wire
		(pts
			(xy 266.7 182.88) (xy 266.7 184.15)
		)
		(stroke
			(width 0)
			(type default)
		)
	)
	(wire
		(pts
			(xy 140.97 209.55) (xy 140.97 213.36)
		)
		(stroke
			(width 0)
			(type default)
		)
	)
	(wire
		(pts
			(xy 153.67 193.04) (xy 154.94 193.04)
		)
		(stroke
			(width 0)
			(type default)
		)
	)
	(wire
		(pts
			(xy 58.42 198.12) (xy 69.85 198.12)
		)
		(stroke
			(width 0)
			(type default)
		)
	)
	(wire
		(pts
			(xy 176.53 195.58) (xy 195.58 195.58)
		)
		(stroke
			(width 0)
			(type default)
		)
	)
	(wire
		(pts
			(xy 306.07 236.22) (xy 306.07 237.49)
		)
		(stroke
			(width 0)
			(type default)
		)
	)
	(wire
		(pts
			(xy 207.01 76.2) (xy 213.36 76.2)
		)
		(stroke
			(width 0)
			(type default)
		)
	)
	(wire
		(pts
			(xy 134.62 215.9) (xy 128.27 215.9)
		)
		(stroke
			(width 0)
			(type default)
		)
	)
	(wire
		(pts
			(xy 143.51 209.55) (xy 143.51 213.36)
		)
		(stroke
			(width 0)
			(type default)
		)
	)
	(wire
		(pts
			(xy 247.65 182.88) (xy 266.7 182.88)
		)
		(stroke
			(width 0)
			(type default)
		)
	)
	(wire
		(pts
			(xy 207.01 86.36) (xy 209.55 86.36)
		)
		(stroke
			(width 0)
			(type default)
		)
	)
	(wire
		(pts
			(xy 128.27 215.9) (xy 128.27 218.44)
		)
		(stroke
			(width 0)
			(type default)
		)
	)
	(wire
		(pts
			(xy 153.67 182.88) (xy 153.67 193.04)
		)
		(stroke
			(width 0)
			(type default)
		)
	)
	(bus
		(pts
			(xy 151.13 39.37) (xy 246.38 39.37)
		)
		(stroke
			(width 0)
			(type default)
		)
	)
	(wire
		(pts
			(xy 247.65 182.88) (xy 247.65 185.42)
		)
		(stroke
			(width 0)
			(type default)
		)
	)
	(wire
		(pts
			(xy 58.42 187.96) (xy 69.85 187.96)
		)
		(stroke
			(width 0)
			(type default)
		)
	)
	(wire
		(pts
			(xy 207.01 73.66) (xy 208.28 73.66)
		)
		(stroke
			(width 0)
			(type default)
		)
	)
	(wire
		(pts
			(xy 275.59 199.39) (xy 275.59 194.31)
		)
		(stroke
			(width 0)
			(type default)
		)
	)
	(wire
		(pts
			(xy 266.7 182.88) (xy 287.02 182.88)
		)
		(stroke
			(width 0)
			(type default)
		)
	)
	(wire
		(pts
			(xy 128.27 213.36) (xy 128.27 215.9)
		)
		(stroke
			(width 0)
			(type default)
		)
	)
	(wire
		(pts
			(xy 340.36 193.04) (xy 340.36 198.12)
		)
		(stroke
			(width 0)
			(type default)
		)
	)
	(wire
		(pts
			(xy 349.25 182.88) (xy 349.25 187.96)
		)
		(stroke
			(width 0)
			(type default)
		)
	)
	(wire
		(pts
			(xy 209.55 93.98) (xy 209.55 95.25)
		)
		(stroke
			(width 0)
			(type default)
		)
	)
	(wire
		(pts
			(xy 302.26 190.5) (xy 307.34 190.5)
		)
		(stroke
			(width 0)
			(type default)
		)
	)
	(wire
		(pts
			(xy 179.07 223.52) (xy 179.07 226.06)
		)
		(stroke
			(width 0)
			(type default)
		)
	)
	(wire
		(pts
			(xy 224.79 182.88) (xy 224.79 189.23)
		)
		(stroke
			(width 0)
			(type default)
		)
	)
	(wire
		(pts
			(xy 331.47 190.5) (xy 331.47 191.77)
		)
		(stroke
			(width 0)
			(type default)
		)
	)
	(wire
		(pts
			(xy 160.02 78.74) (xy 185.42 78.74)
		)
		(stroke
			(width 0)
			(type default)
		)
	)
	(wire
		(pts
			(xy 285.75 236.22) (xy 284.48 236.22)
		)
		(stroke
			(width 0)
			(type default)
		)
	)
	(wire
		(pts
			(xy 139.7 215.9) (xy 154.94 215.9)
		)
		(stroke
			(width 0)
			(type default)
		)
	)
	(wire
		(pts
			(xy 153.67 68.58) (xy 185.42 68.58)
		)
		(stroke
			(width 0)
			(type default)
		)
	)
	(bus
		(pts
			(xy 151.13 39.37) (xy 151.13 48.26)
		)
		(stroke
			(width 0)
			(type default)
		)
	)
	(wire
		(pts
			(xy 181.61 76.2) (xy 185.42 76.2)
		)
		(stroke
			(width 0)
			(type default)
		)
	)
	(wire
		(pts
			(xy 154.94 208.28) (xy 153.67 208.28)
		)
		(stroke
			(width 0)
			(type default)
		)
	)
	(wire
		(pts
			(xy 349.25 193.04) (xy 349.25 198.12)
		)
		(stroke
			(width 0)
			(type default)
		)
	)
	(wire
		(pts
			(xy 218.44 93.98) (xy 218.44 95.25)
		)
		(stroke
			(width 0)
			(type default)
		)
	)
	(wire
		(pts
			(xy 208.28 73.66) (xy 208.28 78.74)
		)
		(stroke
			(width 0)
			(type default)
		)
	)
	(wire
		(pts
			(xy 176.53 223.52) (xy 179.07 223.52)
		)
		(stroke
			(width 0)
			(type default)
		)
	)
	(wire
		(pts
			(xy 204.47 189.23) (xy 204.47 198.12)
		)
		(stroke
			(width 0)
			(type default)
		)
	)
	(wire
		(pts
			(xy 358.14 193.04) (xy 358.14 198.12)
		)
		(stroke
			(width 0)
			(type default)
		)
	)
	(wire
		(pts
			(xy 139.7 220.98) (xy 154.94 220.98)
		)
		(stroke
			(width 0)
			(type default)
		)
	)
	(wire
		(pts
			(xy 58.42 177.8) (xy 69.85 177.8)
		)
		(stroke
			(width 0)
			(type default)
		)
	)
	(wire
		(pts
			(xy 287.02 194.31) (xy 287.02 198.12)
		)
		(stroke
			(width 0)
			(type default)
		)
	)
	(wire
		(pts
			(xy 218.44 76.2) (xy 243.84 76.2)
		)
		(stroke
			(width 0)
			(type default)
		)
	)
	(wire
		(pts
			(xy 367.03 182.88) (xy 372.11 182.88)
		)
		(stroke
			(width 0)
			(type default)
		)
	)
	(wire
		(pts
			(xy 327.66 190.5) (xy 331.47 190.5)
		)
		(stroke
			(width 0)
			(type default)
		)
	)
	(wire
		(pts
			(xy 298.45 236.22) (xy 299.72 236.22)
		)
		(stroke
			(width 0)
			(type default)
		)
	)
	(wire
		(pts
			(xy 185.42 213.36) (xy 199.39 213.36)
		)
		(stroke
			(width 0)
			(type default)
		)
	)
	(wire
		(pts
			(xy 88.9 182.88) (xy 97.79 182.88)
		)
		(stroke
			(width 0)
			(type default)
		)
	)
	(wire
		(pts
			(xy 128.27 220.98) (xy 134.62 220.98)
		)
		(stroke
			(width 0)
			(type default)
		)
	)
	(wire
		(pts
			(xy 102.87 182.88) (xy 113.03 182.88)
		)
		(stroke
			(width 0)
			(type default)
		)
	)
	(wire
		(pts
			(xy 298.45 232.41) (xy 309.88 232.41)
		)
		(stroke
			(width 0)
			(type default)
		)
	)
	(wire
		(pts
			(xy 349.25 182.88) (xy 358.14 182.88)
		)
		(stroke
			(width 0)
			(type default)
		)
	)
	(wire
		(pts
			(xy 331.47 182.88) (xy 340.36 182.88)
		)
		(stroke
			(width 0)
			(type default)
		)
	)
	(wire
		(pts
			(xy 88.9 182.88) (xy 88.9 203.2)
		)
		(stroke
			(width 0)
			(type default)
		)
	)
	(wire
		(pts
			(xy 328.93 185.42) (xy 328.93 182.88)
		)
		(stroke
			(width 0)
			(type default)
		)
	)
	(wire
		(pts
			(xy 185.42 81.28) (xy 160.02 81.28)
		)
		(stroke
			(width 0)
			(type default)
		)
	)
	(wire
		(pts
			(xy 153.67 53.34) (xy 185.42 53.34)
		)
		(stroke
			(width 0)
			(type default)
		)
	)
	(wire
		(pts
			(xy 153.67 208.28) (xy 153.67 210.82)
		)
		(stroke
			(width 0)
			(type default)
		)
	)
	(wire
		(pts
			(xy 327.66 198.12) (xy 328.93 198.12)
		)
		(stroke
			(width 0)
			(type default)
		)
	)
	(wire
		(pts
			(xy 140.97 200.66) (xy 154.94 200.66)
		)
		(stroke
			(width 0)
			(type default)
		)
	)
	(wire
		(pts
			(xy 266.7 194.31) (xy 266.7 207.01)
		)
		(stroke
			(width 0)
			(type default)
		)
	)
	(wire
		(pts
			(xy 204.47 182.88) (xy 204.47 184.15)
		)
		(stroke
			(width 0)
			(type default)
		)
	)
	(wire
		(pts
			(xy 153.67 66.04) (xy 185.42 66.04)
		)
		(stroke
			(width 0)
			(type default)
		)
	)
	(wire
		(pts
			(xy 367.03 182.88) (xy 367.03 187.96)
		)
		(stroke
			(width 0)
			(type default)
		)
	)
	(wire
		(pts
			(xy 217.17 182.88) (xy 217.17 189.23)
		)
		(stroke
			(width 0)
			(type default)
		)
	)
	(wire
		(pts
			(xy 238.76 194.31) (xy 238.76 201.93)
		)
		(stroke
			(width 0)
			(type default)
		)
	)
	(bus
		(pts
			(xy 151.13 48.26) (xy 151.13 50.8)
		)
		(stroke
			(width 0)
			(type default)
		)
	)
	(wire
		(pts
			(xy 185.42 83.82) (xy 160.02 83.82)
		)
		(stroke
			(width 0)
			(type default)
		)
	)
	(wire
		(pts
			(xy 331.47 196.85) (xy 331.47 198.12)
		)
		(stroke
			(width 0)
			(type default)
		)
	)
	(wire
		(pts
			(xy 275.59 194.31) (xy 287.02 194.31)
		)
		(stroke
			(width 0)
			(type default)
		)
	)
	(wire
		(pts
			(xy 118.11 182.88) (xy 137.16 182.88)
		)
		(stroke
			(width 0)
			(type default)
		)
	)
	(bus
		(pts
			(xy 151.13 58.42) (xy 151.13 60.96)
		)
		(stroke
			(width 0)
			(type default)
		)
	)
	(wire
		(pts
			(xy 185.42 189.23) (xy 185.42 193.04)
		)
		(stroke
			(width 0)
			(type default)
		)
	)
	(wire
		(pts
			(xy 143.51 203.2) (xy 143.51 204.47)
		)
		(stroke
			(width 0)
			(type default)
		)
	)
	(wire
		(pts
			(xy 287.02 189.23) (xy 287.02 194.31)
		)
		(stroke
			(width 0)
			(type default)
		)
	)
	(wire
		(pts
			(xy 140.97 200.66) (xy 140.97 204.47)
		)
		(stroke
			(width 0)
			(type default)
		)
	)
	(wire
		(pts
			(xy 238.76 182.88) (xy 238.76 189.23)
		)
		(stroke
			(width 0)
			(type default)
		)
	)
	(wire
		(pts
			(xy 287.02 203.2) (xy 287.02 217.17)
		)
		(stroke
			(width 0)
			(type default)
		)
	)
	(wire
		(pts
			(xy 218.44 81.28) (xy 243.84 81.28)
		)
		(stroke
			(width 0)
			(type default)
		)
	)
	(wire
		(pts
			(xy 274.32 194.31) (xy 275.59 194.31)
		)
		(stroke
			(width 0)
			(type default)
		)
	)
	(wire
		(pts
			(xy 195.58 182.88) (xy 204.47 182.88)
		)
		(stroke
			(width 0)
			(type default)
		)
	)
	(wire
		(pts
			(xy 358.14 198.12) (xy 367.03 198.12)
		)
		(stroke
			(width 0)
			(type default)
		)
	)
	(wire
		(pts
			(xy 128.27 213.36) (xy 140.97 213.36)
		)
		(stroke
			(width 0)
			(type default)
		)
	)
	(wire
		(pts
			(xy 137.16 182.88) (xy 149.86 182.88)
		)
		(stroke
			(width 0)
			(type default)
		)
	)
	(wire
		(pts
			(xy 304.8 198.12) (xy 307.34 198.12)
		)
		(stroke
			(width 0)
			(type default)
		)
	)
	(wire
		(pts
			(xy 149.86 195.58) (xy 154.94 195.58)
		)
		(stroke
			(width 0)
			(type default)
		)
	)
	(wire
		(pts
			(xy 118.11 182.88) (xy 118.11 190.5)
		)
		(stroke
			(width 0)
			(type default)
		)
	)
	(wire
		(pts
			(xy 247.65 190.5) (xy 247.65 193.04)
		)
		(stroke
			(width 0)
			(type default)
		)
	)
	(wire
		(pts
			(xy 207.01 81.28) (xy 213.36 81.28)
		)
		(stroke
			(width 0)
			(type default)
		)
	)
	(wire
		(pts
			(xy 331.47 189.23) (xy 331.47 190.5)
		)
		(stroke
			(width 0)
			(type default)
		)
	)
	(wire
		(pts
			(xy 113.03 195.58) (xy 113.03 213.36)
		)
		(stroke
			(width 0)
			(type default)
		)
	)
	(wire
		(pts
			(xy 181.61 93.98) (xy 181.61 95.25)
		)
		(stroke
			(width 0)
			(type default)
		)
	)
	(wire
		(pts
			(xy 153.67 210.82) (xy 154.94 210.82)
		)
		(stroke
			(width 0)
			(type default)
		)
	)
	(wire
		(pts
			(xy 69.85 182.88) (xy 68.58 182.88)
		)
		(stroke
			(width 0)
			(type default)
		)
	)
	(wire
		(pts
			(xy 128.27 212.09) (xy 128.27 213.36)
		)
		(stroke
			(width 0)
			(type default)
		)
	)
	(wire
		(pts
			(xy 68.58 213.36) (xy 97.79 213.36)
		)
		(stroke
			(width 0)
			(type default)
		)
	)
	(wire
		(pts
			(xy 149.86 182.88) (xy 149.86 184.15)
		)
		(stroke
			(width 0)
			(type default)
		)
	)
	(wire
		(pts
			(xy 266.7 207.01) (xy 266.7 210.82)
		)
		(stroke
			(width 0)
			(type default)
		)
	)
	(wire
		(pts
			(xy 327.66 185.42) (xy 328.93 185.42)
		)
		(stroke
			(width 0)
			(type default)
		)
	)
	(wire
		(pts
			(xy 153.67 63.5) (xy 185.42 63.5)
		)
		(stroke
			(width 0)
			(type default)
		)
	)
	(wire
		(pts
			(xy 176.53 213.36) (xy 180.34 213.36)
		)
		(stroke
			(width 0)
			(type default)
		)
	)
	(wire
		(pts
			(xy 349.25 198.12) (xy 358.14 198.12)
		)
		(stroke
			(width 0)
			(type default)
		)
	)
	(wire
		(pts
			(xy 176.53 193.04) (xy 185.42 193.04)
		)
		(stroke
			(width 0)
			(type default)
		)
	)
	(wire
		(pts
			(xy 204.47 182.88) (xy 217.17 182.88)
		)
		(stroke
			(width 0)
			(type default)
		)
	)
	(wire
		(pts
			(xy 327.66 182.88) (xy 328.93 182.88)
		)
		(stroke
			(width 0)
			(type default)
		)
	)
	(wire
		(pts
			(xy 367.03 181.61) (xy 367.03 182.88)
		)
		(stroke
			(width 0)
			(type default)
		)
	)
	(wire
		(pts
			(xy 137.16 181.61) (xy 137.16 182.88)
		)
		(stroke
			(width 0)
			(type default)
		)
	)
	(wire
		(pts
			(xy 231.14 182.88) (xy 238.76 182.88)
		)
		(stroke
			(width 0)
			(type default)
		)
	)
	(bus
		(pts
			(xy 151.13 50.8) (xy 151.13 53.34)
		)
		(stroke
			(width 0)
			(type default)
		)
	)
	(wire
		(pts
			(xy 87.63 182.88) (xy 88.9 182.88)
		)
		(stroke
			(width 0)
			(type default)
		)
	)
	(bus
		(pts
			(xy 151.13 63.5) (xy 151.13 66.04)
		)
		(stroke
			(width 0)
			(type default)
		)
	)
	(wire
		(pts
			(xy 217.17 182.88) (xy 224.79 182.88)
		)
		(stroke
			(width 0)
			(type default)
		)
	)
	(wire
		(pts
			(xy 328.93 195.58) (xy 328.93 198.12)
		)
		(stroke
			(width 0)
			(type default)
		)
	)
	(wire
		(pts
			(xy 153.67 182.88) (xy 185.42 182.88)
		)
		(stroke
			(width 0)
			(type default)
		)
	)
	(wire
		(pts
			(xy 113.03 182.88) (xy 118.11 182.88)
		)
		(stroke
			(width 0)
			(type default)
		)
	)
	(wire
		(pts
			(xy 134.62 218.44) (xy 128.27 218.44)
		)
		(stroke
			(width 0)
			(type default)
		)
	)
	(wire
		(pts
			(xy 113.03 182.88) (xy 113.03 190.5)
		)
		(stroke
			(width 0)
			(type default)
		)
	)
	(wire
		(pts
			(xy 153.67 58.42) (xy 185.42 58.42)
		)
		(stroke
			(width 0)
			(type default)
		)
	)
	(wire
		(pts
			(xy 266.7 207.01) (xy 269.24 207.01)
		)
		(stroke
			(width 0)
			(type default)
		)
	)
	(bus
		(pts
			(xy 137.16 39.37) (xy 151.13 39.37)
		)
		(stroke
			(width 0)
			(type default)
		)
	)
	(wire
		(pts
			(xy 207.01 78.74) (xy 208.28 78.74)
		)
		(stroke
			(width 0)
			(type default)
		)
	)
	(wire
		(pts
			(xy 287.02 182.88) (xy 300.99 182.88)
		)
		(stroke
			(width 0)
			(type default)
		)
	)
	(wire
		(pts
			(xy 176.53 198.12) (xy 204.47 198.12)
		)
		(stroke
			(width 0)
			(type default)
		)
	)
	(wire
		(pts
			(xy 255.27 207.01) (xy 266.7 207.01)
		)
		(stroke
			(width 0)
			(type default)
		)
	)
	(bus
		(pts
			(xy 151.13 60.96) (xy 151.13 63.5)
		)
		(stroke
			(width 0)
			(type default)
		)
	)
	(wire
		(pts
			(xy 185.42 182.88) (xy 195.58 182.88)
		)
		(stroke
			(width 0)
			(type default)
		)
	)
	(wire
		(pts
			(xy 118.11 195.58) (xy 118.11 213.36)
		)
		(stroke
			(width 0)
			(type default)
		)
	)
	(wire
		(pts
			(xy 68.58 203.2) (xy 69.85 203.2)
		)
		(stroke
			(width 0)
			(type default)
		)
	)
	(wire
		(pts
			(xy 153.67 213.36) (xy 154.94 213.36)
		)
		(stroke
			(width 0)
			(type default)
		)
	)
	(wire
		(pts
			(xy 195.58 182.88) (xy 195.58 184.15)
		)
		(stroke
			(width 0)
			(type default)
		)
	)
	(wire
		(pts
			(xy 113.03 213.36) (xy 118.11 213.36)
		)
		(stroke
			(width 0)
			(type default)
		)
	)
	(wire
		(pts
			(xy 266.7 194.31) (xy 269.24 194.31)
		)
		(stroke
			(width 0)
			(type default)
		)
	)
	(wire
		(pts
			(xy 300.99 182.88) (xy 307.34 182.88)
		)
		(stroke
			(width 0)
			(type default)
		)
	)
	(wire
		(pts
			(xy 266.7 215.9) (xy 266.7 217.17)
		)
		(stroke
			(width 0)
			(type default)
		)
	)
	(wire
		(pts
			(xy 327.66 195.58) (xy 328.93 195.58)
		)
		(stroke
			(width 0)
			(type default)
		)
	)
	(wire
		(pts
			(xy 217.17 194.31) (xy 217.17 201.93)
		)
		(stroke
			(width 0)
			(type default)
		)
	)
	(wire
		(pts
			(xy 143.51 213.36) (xy 153.67 213.36)
		)
		(stroke
			(width 0)
			(type default)
		)
	)
	(wire
		(pts
			(xy 224.79 194.31) (xy 224.79 201.93)
		)
		(stroke
			(width 0)
			(type default)
		)
	)
	(wire
		(pts
			(xy 231.14 182.88) (xy 231.14 189.23)
		)
		(stroke
			(width 0)
			(type default)
		)
	)
	(wire
		(pts
			(xy 328.93 182.88) (xy 331.47 182.88)
		)
		(stroke
			(width 0)
			(type default)
		)
	)
	(wire
		(pts
			(xy 185.42 182.88) (xy 185.42 184.15)
		)
		(stroke
			(width 0)
			(type default)
		)
	)
	(wire
		(pts
			(xy 278.13 236.22) (xy 278.13 237.49)
		)
		(stroke
			(width 0)
			(type default)
		)
	)
	(bus
		(pts
			(xy 151.13 55.88) (xy 151.13 58.42)
		)
		(stroke
			(width 0)
			(type default)
		)
	)
	(polyline
		(pts
			(xy 12.7 134.62) (xy 407.67 134.62)
		)
		(stroke
			(width 0)
			(type default)
		)
	)
	(wire
		(pts
			(xy 185.42 73.66) (xy 181.61 73.66)
		)
		(stroke
			(width 0)
			(type default)
		)
	)
	(wire
		(pts
			(xy 367.03 198.12) (xy 367.03 199.39)
		)
		(stroke
			(width 0)
			(type default)
		)
	)
	(wire
		(pts
			(xy 285.75 232.41) (xy 273.05 232.41)
		)
		(stroke
			(width 0)
			(type default)
		)
	)
	(wire
		(pts
			(xy 179.07 226.06) (xy 179.07 234.95)
		)
		(stroke
			(width 0)
			(type default)
		)
	)
	(wire
		(pts
			(xy 153.67 50.8) (xy 185.42 50.8)
		)
		(stroke
			(width 0)
			(type default)
		)
	)
	(wire
		(pts
			(xy 58.42 208.28) (xy 69.85 208.28)
		)
		(stroke
			(width 0)
			(type default)
		)
	)
	(wire
		(pts
			(xy 185.42 86.36) (xy 160.02 86.36)
		)
		(stroke
			(width 0)
			(type default)
		)
	)
	(wire
		(pts
			(xy 266.7 189.23) (xy 266.7 194.31)
		)
		(stroke
			(width 0)
			(type default)
		)
	)
	(wire
		(pts
			(xy 139.7 218.44) (xy 154.94 218.44)
		)
		(stroke
			(width 0)
			(type default)
		)
	)
	(wire
		(pts
			(xy 181.61 73.66) (xy 181.61 76.2)
		)
		(stroke
			(width 0)
			(type default)
		)
	)
	(wire
		(pts
			(xy 179.07 226.06) (xy 176.53 226.06)
		)
		(stroke
			(width 0)
			(type default)
		)
	)
	(wire
		(pts
			(xy 153.67 210.82) (xy 153.67 213.36)
		)
		(stroke
			(width 0)
			(type default)
		)
	)
	(wire
		(pts
			(xy 287.02 182.88) (xy 287.02 184.15)
		)
		(stroke
			(width 0)
			(type default)
		)
	)
	(wire
		(pts
			(xy 275.59 209.55) (xy 275.59 217.17)
		)
		(stroke
			(width 0)
			(type default)
		)
	)
	(wire
		(pts
			(xy 328.93 198.12) (xy 331.47 198.12)
		)
		(stroke
			(width 0)
			(type default)
		)
	)
	(wire
		(pts
			(xy 153.67 60.96) (xy 185.42 60.96)
		)
		(stroke
			(width 0)
			(type default)
		)
	)
	(wire
		(pts
			(xy 118.11 213.36) (xy 128.27 213.36)
		)
		(stroke
			(width 0)
			(type default)
		)
	)
	(wire
		(pts
			(xy 218.44 88.9) (xy 218.44 86.36)
		)
		(stroke
			(width 0)
			(type default)
		)
	)
	(wire
		(pts
			(xy 331.47 182.88) (xy 331.47 184.15)
		)
		(stroke
			(width 0)
			(type default)
		)
	)
	(wire
		(pts
			(xy 358.14 182.88) (xy 358.14 187.96)
		)
		(stroke
			(width 0)
			(type default)
		)
	)
	(wire
		(pts
			(xy 153.67 55.88) (xy 185.42 55.88)
		)
		(stroke
			(width 0)
			(type default)
		)
	)
	(wire
		(pts
			(xy 231.14 194.31) (xy 231.14 201.93)
		)
		(stroke
			(width 0)
			(type default)
		)
	)
	(wire
		(pts
			(xy 358.14 182.88) (xy 367.03 182.88)
		)
		(stroke
			(width 0)
			(type default)
		)
	)
	(wire
		(pts
			(xy 68.58 203.2) (xy 68.58 213.36)
		)
		(stroke
			(width 0)
			(type default)
		)
	)
	(wire
		(pts
			(xy 287.02 194.31) (xy 302.26 194.31)
		)
		(stroke
			(width 0)
			(type default)
		)
	)
	(wire
		(pts
			(xy 304.8 236.22) (xy 306.07 236.22)
		)
		(stroke
			(width 0)
			(type default)
		)
	)
	(wire
		(pts
			(xy 149.86 189.23) (xy 149.86 195.58)
		)
		(stroke
			(width 0)
			(type default)
		)
	)
	(label "ETHERNET.LED_ACT"
		(at 224.79 76.2 0)
		(effects
			(font
				(size 1.27 1.27)
			)
			(justify left bottom)
		)
	)
	(label "PAIR_12"
		(at 160.02 78.74 0)
		(effects
			(font
				(size 1.27 1.27)
			)
			(justify left bottom)
		)
	)
	(label "ETHERNET.D0_P"
		(at 154.94 50.8 0)
		(effects
			(font
				(size 1.27 1.27)
			)
			(justify left bottom)
		)
	)
	(label "PAIR_36"
		(at 160.02 81.28 0)
		(effects
			(font
				(size 1.27 1.27)
			)
			(justify left bottom)
		)
	)
	(label "POE_ACTIVE"
		(at 273.05 232.41 0)
		(effects
			(font
				(size 1.27 1.27)
			)
			(justify left bottom)
		)
	)
	(label "TPL"
		(at 179.07 195.58 0)
		(effects
			(font
				(size 1.27 1.27)
			)
			(justify left bottom)
		)
	)
	(label "PAIR_36"
		(at 58.42 187.96 0)
		(effects
			(font
				(size 1.27 1.27)
			)
			(justify left bottom)
		)
	)
	(label "POE_ACTIVE"
		(at 255.27 207.01 0)
		(effects
			(font
				(size 1.27 1.27)
			)
			(justify left bottom)
		)
	)
	(label "ETHERNET.LED_LINK"
		(at 224.79 81.28 0)
		(effects
			(font
				(size 1.27 1.27)
			)
			(justify left bottom)
		)
	)
	(label "REF"
		(at 154.94 218.44 180)
		(effects
			(font
				(size 1.27 1.27)
			)
			(justify right bottom)
		)
	)
	(label "CLSA"
		(at 143.51 200.66 0)
		(effects
			(font
				(size 1.27 1.27)
			)
			(justify left bottom)
		)
	)
	(label "PG"
		(at 180.34 213.36 180)
		(effects
			(font
				(size 1.27 1.27)
			)
			(justify right bottom)
		)
	)
	(label "POE_ACTIVE"
		(at 199.39 213.36 180)
		(effects
			(font
				(size 1.27 1.27)
			)
			(justify right bottom)
		)
	)
	(label "ETHERNET.D1_P"
		(at 154.94 55.88 0)
		(effects
			(font
				(size 1.27 1.27)
			)
			(justify left bottom)
		)
	)
	(label "PAIR_78"
		(at 58.42 208.28 0)
		(effects
			(font
				(size 1.27 1.27)
			)
			(justify left bottom)
		)
	)
	(label "DEN"
		(at 154.94 195.58 180)
		(effects
			(font
				(size 1.27 1.27)
			)
			(justify right bottom)
		)
	)
	(label "ETHERNET.D0_N"
		(at 154.94 53.34 0)
		(effects
			(font
				(size 1.27 1.27)
			)
			(justify left bottom)
		)
	)
	(label "ETHERNET.D2_P"
		(at 154.94 60.96 0)
		(effects
			(font
				(size 1.27 1.27)
			)
			(justify left bottom)
		)
	)
	(label "~{BT}"
		(at 179.07 198.12 0)
		(effects
			(font
				(size 1.27 1.27)
			)
			(justify left bottom)
		)
	)
	(label "ETHERNET.D3_P"
		(at 154.94 66.04 0)
		(effects
			(font
				(size 1.27 1.27)
			)
			(justify left bottom)
		)
	)
	(label "ETHERNET.D1_N"
		(at 154.94 58.42 0)
		(effects
			(font
				(size 1.27 1.27)
			)
			(justify left bottom)
		)
	)
	(label "ETHERNET.D3_N"
		(at 154.94 68.58 0)
		(effects
			(font
				(size 1.27 1.27)
			)
			(justify left bottom)
		)
	)
	(label "TPH"
		(at 179.07 193.04 0)
		(effects
			(font
				(size 1.27 1.27)
			)
			(justify left bottom)
		)
	)
	(label "CLSB"
		(at 148.59 203.2 180)
		(effects
			(font
				(size 1.27 1.27)
			)
			(justify right bottom)
		)
	)
	(label "PAIR_12"
		(at 58.42 177.8 0)
		(effects
			(font
				(size 1.27 1.27)
			)
			(justify left bottom)
		)
	)
	(label "PAIR_78"
		(at 160.02 83.82 0)
		(effects
			(font
				(size 1.27 1.27)
			)
			(justify left bottom)
		)
	)
	(label "ETHERNET.D2_N"
		(at 154.94 63.5 0)
		(effects
			(font
				(size 1.27 1.27)
			)
			(justify left bottom)
		)
	)
	(label "VSS"
		(at 121.92 213.36 0)
		(effects
			(font
				(size 1.27 1.27)
			)
			(justify left bottom)
		)
	)
	(label "ULS-12_CTRL"
		(at 288.29 194.31 0)
		(effects
			(font
				(size 1.27 1.27)
			)
			(justify left bottom)
		)
	)
	(label "PAIR_910"
		(at 58.42 198.12 0)
		(effects
			(font
				(size 1.27 1.27)
			)
			(justify left bottom)
		)
	)
	(label "VDD"
		(at 121.92 182.88 0)
		(effects
			(font
				(size 1.27 1.27)
			)
			(justify left bottom)
		)
	)
	(label "AMPS_CTL"
		(at 154.94 215.9 180)
		(effects
			(font
				(size 1.27 1.27)
			)
			(justify right bottom)
		)
	)
	(label "MPS_DUTY"
		(at 154.94 220.98 180)
		(effects
			(font
				(size 1.27 1.27)
			)
			(justify right bottom)
		)
	)
	(label "PAIR_910"
		(at 160.02 86.36 0)
		(effects
			(font
				(size 1.27 1.27)
			)
			(justify left bottom)
		)
	)
	(hierarchical_label "~{POE EN}"
		(shape input)
		(at 309.88 232.41 0)
		(effects
			(font
				(size 1.27 1.27)
			)
			(justify left)
		)
	)
	(hierarchical_label "POE_12V"
		(shape output)
		(at 372.11 182.88 0)
		(effects
			(font
				(size 1.27 1.27)
			)
			(justify left)
		)
	)
	(hierarchical_label "ETHERNET{Ethernet}"
		(shape bidirectional)
		(at 137.16 39.37 180)
		(effects
			(font
				(size 1.27 1.27)
				(bold yes)
			)
			(justify right)
		)
	)
	(symbol
		(lib_id "antmicroLEDIndicationDiscrete:LED_G_0603_KP-1608CGCK")
		(at 247.65 198.12 270)
		(mirror x)
		(unit 1)
		(exclude_from_sim no)
		(in_bom yes)
		(on_board yes)
		(dnp no)
		(property "Reference" "D404"
			(at 254 194.31 90)
			(effects
				(font
					(size 1.27 1.27)
					(thickness 0.15)
				)
			)
		)
		(property "Value" "LED_G_0603_KP-1608CGCK"
			(at 240.03 175.26 0)
			(effects
				(font
					(size 1.27 1.27)
					(thickness 0.15)
				)
				(justify left bottom)
				(hide yes)
			)
		)
		(property "Footprint" "antmicro-footprints:LED_0603_1608Metric_G"
			(at 237.49 175.26 0)
			(effects
				(font
					(size 1.27 1.27)
					(thickness 0.15)
				)
				(justify left bottom)
				(hide yes)
			)
		)
		(property "Datasheet" "http://www.kingbright.com/attachments/file/psearch//000/00/00/KP-1608CGCK(Ver.23B).pdf"
			(at 234.95 175.26 0)
			(effects
				(font
					(size 1.27 1.27)
					(thickness 0.15)
				)
				(justify left bottom)
				(hide yes)
			)
		)
		(property "Description" ""
			(at 247.65 198.12 0)
			(effects
				(font
					(size 1.27 1.27)
				)
				(hide yes)
			)
		)
		(property "MPN" "KP-1608CGCK"
			(at 232.41 175.26 0)
			(effects
				(font
					(size 1.27 1.27)
					(thickness 0.15)
				)
				(justify left bottom)
				(hide yes)
			)
		)
		(property "Manufacturer" "Kingbright"
			(at 229.87 175.26 0)
			(effects
				(font
					(size 1.27 1.27)
					(thickness 0.15)
				)
				(justify left bottom)
				(hide yes)
			)
		)
		(property "Color" "Green"
			(at 254 196.85 90)
			(effects
				(font
					(size 1.27 1.27)
				)
			)
		)
		(property "Author" "Antmicro"
			(at 227.33 175.26 0)
			(effects
				(font
					(size 1.27 1.27)
					(thickness 0.15)
				)
				(justify left bottom)
				(hide yes)
			)
		)
		(property "License" "Apache-2.0"
			(at 224.79 175.26 0)
			(effects
				(font
					(size 1.27 1.27)
					(thickness 0.15)
				)
				(justify left bottom)
				(hide yes)
			)
		)
		(pin "2"
		)
		(pin "1"
		)
		(instances
			(project "cm4-baseboard"
				(path ""
					(reference "D404")
					(unit 1)
				)
			)
		)
	)
	(symbol
		(lib_id "antmicropower:PWR_FLAG")
		(at 137.16 181.61 0)
		(unit 1)
		(exclude_from_sim no)
		(in_bom yes)
		(on_board yes)
		(dnp no)
		(property "Reference" "#FLG010"
			(at 137.16 179.705 0)
			(effects
				(font
					(size 1.27 1.27)
				)
				(hide yes)
			)
		)
		(property "Value" "PWR_FLAG"
			(at 137.16 177.8 0)
			(effects
				(font
					(size 1.27 1.27)
				)
			)
		)
		(property "Footprint" ""
			(at 137.16 181.61 0)
			(effects
				(font
					(size 1.27 1.27)
				)
				(hide yes)
			)
		)
		(property "Datasheet" ""
			(at 137.16 181.61 0)
			(effects
				(font
					(size 1.27 1.27)
				)
				(hide yes)
			)
		)
		(property "Description" ""
			(at 137.16 181.61 0)
			(effects
				(font
					(size 1.27 1.27)
				)
				(hide yes)
			)
		)
		(pin "1"
		)
		(instances
			(project "cm4-baseboard"
				(path ""
					(reference "#FLG010")
					(unit 1)
				)
			)
		)
	)
	(symbol
		(lib_id "antmicroResistors0402:R_24k9_0402")
		(at 149.86 189.23 90)
		(unit 1)
		(exclude_from_sim no)
		(in_bom yes)
		(on_board yes)
		(dnp no)
		(fields_autoplaced yes)
		(property "Reference" "R406"
			(at 147.32 185.4199 90)
			(effects
				(font
					(size 1.27 1.27)
				)
				(justify left)
			)
		)
		(property "Value" "R_24k9_0402"
			(at 162.56 168.91 0)
			(effects
				(font
					(size 1.27 1.27)
					(thickness 0.15)
				)
				(justify left bottom)
				(hide yes)
			)
		)
		(property "Footprint" "antmicro-footprints:R_0402_1005Metric"
			(at 165.1 168.91 0)
			(effects
				(font
					(size 1.27 1.27)
					(thickness 0.15)
				)
				(justify left bottom)
				(hide yes)
			)
		)
		(property "Datasheet" "https://www.bourns.com/docs/product-datasheets/cr.pdf"
			(at 167.64 168.91 0)
			(effects
				(font
					(size 1.27 1.27)
					(thickness 0.15)
				)
				(justify left bottom)
				(hide yes)
			)
		)
		(property "Description" ""
			(at 149.86 189.23 0)
			(effects
				(font
					(size 1.27 1.27)
				)
				(hide yes)
			)
		)
		(property "Manufacturer" "Bourns"
			(at 172.72 168.91 0)
			(effects
				(font
					(size 1.27 1.27)
					(thickness 0.15)
				)
				(justify left bottom)
				(hide yes)
			)
		)
		(property "MPN" "CR0402-FX-2492GLF"
			(at 170.18 168.91 0)
			(effects
				(font
					(size 1.27 1.27)
					(thickness 0.15)
				)
				(justify left bottom)
				(hide yes)
			)
		)
		(property "Val" "24k9"
			(at 147.32 187.9599 90)
			(effects
				(font
					(size 1.27 1.27)
					(thickness 0.15)
				)
				(justify left)
			)
		)
		(property "License" "Apache-2.0"
			(at 175.26 168.91 0)
			(effects
				(font
					(size 1.27 1.27)
					(thickness 0.15)
				)
				(justify left bottom)
				(hide yes)
			)
		)
		(property "Author" "Antmicro"
			(at 177.8 168.91 0)
			(effects
				(font
					(size 1.27 1.27)
					(thickness 0.15)
				)
				(justify left bottom)
				(hide yes)
			)
		)
		(property "Tolerance" "1%"
			(at 160.02 168.91 0)
			(effects
				(font
					(size 1.27 1.27)
				)
				(justify left bottom)
				(hide yes)
			)
		)
		(pin "1"
		)
		(pin "2"
		)
		(instances
			(project "cm4-baseboard"
				(path ""
					(reference "R406")
					(unit 1)
				)
			)
		)
	)
	(symbol
		(lib_id "antmicroResistors0402:R_0R_0402")
		(at 331.47 191.77 270)
		(unit 1)
		(exclude_from_sim no)
		(in_bom no)
		(on_board yes)
		(dnp yes)
		(property "Reference" "R423"
			(at 332.74 193.04 90)
			(effects
				(font
					(size 1.27 1.27)
				)
				(justify left)
			)
		)
		(property "Value" "R_0R_0402"
			(at 318.77 212.09 0)
			(effects
				(font
					(size 1.27 1.27)
					(thickness 0.15)
				)
				(justify left bottom)
				(hide yes)
			)
		)
		(property "Footprint" "antmicro-footprints:R_0402_1005Metric"
			(at 316.23 212.09 0)
			(effects
				(font
					(size 1.27 1.27)
					(thickness 0.15)
				)
				(justify left bottom)
				(hide yes)
			)
		)
		(property "Datasheet" "https://industrial.panasonic.com/cdbs/www-data/pdf/RDA0000/AOA0000C301.pdf"
			(at 313.69 212.09 0)
			(effects
				(font
					(size 1.27 1.27)
					(thickness 0.15)
				)
				(justify left bottom)
				(hide yes)
			)
		)
		(property "Description" ""
			(at 331.47 191.77 0)
			(effects
				(font
					(size 1.27 1.27)
				)
				(hide yes)
			)
		)
		(property "Manufacturer" "Panasonic"
			(at 308.61 212.09 0)
			(effects
				(font
					(size 1.27 1.27)
					(thickness 0.15)
				)
				(justify left bottom)
				(hide yes)
			)
		)
		(property "MPN" "ERJ2GE0R00X"
			(at 311.15 212.09 0)
			(effects
				(font
					(size 1.27 1.27)
					(thickness 0.15)
				)
				(justify left bottom)
				(hide yes)
			)
		)
		(property "Val" "0R"
			(at 332.74 195.58 90)
			(effects
				(font
					(size 1.27 1.27)
					(thickness 0.15)
				)
				(justify left)
			)
		)
		(property "License" "Apache-2.0"
			(at 306.07 212.09 0)
			(effects
				(font
					(size 1.27 1.27)
					(thickness 0.15)
				)
				(justify left bottom)
				(hide yes)
			)
		)
		(property "Author" "Antmicro"
			(at 303.53 212.09 0)
			(effects
				(font
					(size 1.27 1.27)
					(thickness 0.15)
				)
				(justify left bottom)
				(hide yes)
			)
		)
		(property "Tolerance" "~"
			(at 321.31 212.09 0)
			(effects
				(font
					(size 1.27 1.27)
				)
				(justify left bottom)
				(hide yes)
			)
		)
		(property "Current" "1A"
			(at 330.2 191.135 0)
			(effects
				(font
					(size 1.27 1.27)
					(thickness 0.15)
				)
				(hide yes)
			)
		)
		(pin "1"
		)
		(pin "2"
		)
		(instances
			(project "cm4-baseboard"
				(path ""
					(reference "R423")
					(unit 1)
				)
			)
		)
	)
	(symbol
		(lib_id "antmicroDCDCConverters:ULS-12_5-D48N-C")
		(at 307.34 182.88 0)
		(unit 1)
		(exclude_from_sim no)
		(in_bom yes)
		(on_board yes)
		(dnp no)
		(property "Reference" "U403"
			(at 317.373 175.26 0)
			(effects
				(font
					(size 1.27 1.27)
				)
			)
		)
		(property "Value" "ULS-12_5-D48N-C"
			(at 340.36 190.5 0)
			(effects
				(font
					(size 1.27 1.27)
					(thickness 0.15)
				)
				(justify left bottom)
				(hide yes)
			)
		)
		(property "Footprint" "antmicro-footprints:Conv_Murata_ULS-60W"
			(at 340.36 193.04 0)
			(effects
				(font
					(size 1.27 1.27)
					(thickness 0.15)
				)
				(justify left bottom)
				(hide yes)
			)
		)
		(property "Datasheet" "https://www.murata.com/products/productdata/8807040286750/uls.pdf?1649388617000"
			(at 340.36 195.58 0)
			(effects
				(font
					(size 1.27 1.27)
					(thickness 0.15)
				)
				(justify left bottom)
				(hide yes)
			)
		)
		(property "Description" "Isolated Through Hole DC/DC Converter, ITE, 2:1, 60 W, 1 Output, 12 V, 5 A"
			(at 307.34 182.88 0)
			(effects
				(font
					(size 1.27 1.27)
				)
				(hide yes)
			)
		)
		(property "Manufacturer" "Murata"
			(at 340.36 198.12 0)
			(effects
				(font
					(size 1.27 1.27)
					(thickness 0.15)
				)
				(justify left bottom)
				(hide yes)
			)
		)
		(property "MPN" "ULS-12/5-D48N-C"
			(at 317.373 177.8 0)
			(effects
				(font
					(size 1.27 1.27)
					(thickness 0.15)
				)
			)
		)
		(property "Author" "Antmicro"
			(at 340.36 200.66 0)
			(effects
				(font
					(size 1.27 1.27)
					(thickness 0.15)
				)
				(justify left bottom)
				(hide yes)
			)
		)
		(property "License" "Apache-2.0"
			(at 340.36 203.2 0)
			(effects
				(font
					(size 1.27 1.27)
					(thickness 0.15)
				)
				(justify left bottom)
				(hide yes)
			)
		)
		(property "Alternatives 50W" " VCB4812SBO-50WR3, V36SE12004NRFA, PKU5513ESI, KHHD004A2B41Z"
			(at 309.88 207.01 0)
			(show_name yes)
			(effects
				(font
					(size 1.27 1.27)
				)
				(justify left)
			)
		)
		(property "Alternatives 75W" " VCB4812SBO-75WR3"
			(at 309.88 209.55 0)
			(show_name yes)
			(effects
				(font
					(size 1.27 1.27)
				)
				(justify left)
			)
		)
		(property "Alternatives 100W" "PKU4913DPIHS, VCB4812SBO-100WFR3"
			(at 309.88 212.09 0)
			(show_name yes)
			(effects
				(font
					(size 1.27 1.27)
				)
				(justify left)
			)
		)
		(property "Alternatives 120W" "PQC50-48-S12-O"
			(at 309.88 214.63 0)
			(show_name yes)
			(effects
				(font
					(size 1.27 1.27)
				)
				(justify left)
			)
		)
		(pin "1"
		)
		(pin "2"
		)
		(pin "3"
		)
		(pin "4"
		)
		(pin "5"
		)
		(pin "6"
		)
		(pin "7"
		)
		(pin "8"
		)
		(instances
			(project "cm4-baseboard"
				(path ""
					(reference "U403")
					(unit 1)
				)
			)
		)
	)
	(symbol
		(lib_id "antmicropower:GNDD")
		(at 231.14 201.93 0)
		(unit 1)
		(exclude_from_sim no)
		(in_bom yes)
		(on_board yes)
		(dnp no)
		(fields_autoplaced yes)
		(property "Reference" "#PWR0408"
			(at 231.14 208.28 0)
			(effects
				(font
					(size 1.27 1.27)
				)
				(justify left bottom)
				(hide yes)
			)
		)
		(property "Value" "GNDD"
			(at 231.14 206.375 0)
			(effects
				(font
					(size 1.27 1.27)
				)
			)
		)
		(property "Footprint" ""
			(at 231.14 201.93 0)
			(effects
				(font
					(size 1.27 1.27)
				)
				(hide yes)
			)
		)
		(property "Datasheet" ""
			(at 231.14 201.93 0)
			(effects
				(font
					(size 1.27 1.27)
				)
				(hide yes)
			)
		)
		(property "Description" ""
			(at 231.14 201.93 0)
			(effects
				(font
					(size 1.27 1.27)
				)
				(hide yes)
			)
		)
		(property "Author" "Antmicro"
			(at 246.38 209.55 0)
			(effects
				(font
					(size 1.27 1.27)
					(thickness 0.15)
				)
				(justify left bottom)
				(hide yes)
			)
		)
		(property "License" "Apache-2.0"
			(at 246.38 212.09 0)
			(effects
				(font
					(size 1.27 1.27)
					(thickness 0.15)
				)
				(justify left bottom)
				(hide yes)
			)
		)
		(pin "1"
		)
		(instances
			(project "cm4-baseboard"
				(path ""
					(reference "#PWR0408")
					(unit 1)
				)
			)
		)
	)
	(symbol
		(lib_id "antmicroResistors0402:R_0R_0402")
		(at 274.32 194.31 180)
		(unit 1)
		(exclude_from_sim no)
		(in_bom no)
		(on_board yes)
		(dnp yes)
		(property "Reference" "R417"
			(at 271.78 190.5 0)
			(effects
				(font
					(size 1.27 1.27)
				)
			)
		)
		(property "Value" "R_0R_0402"
			(at 254 181.61 0)
			(effects
				(font
					(size 1.27 1.27)
					(thickness 0.15)
				)
				(justify left bottom)
				(hide yes)
			)
		)
		(property "Footprint" "antmicro-footprints:R_0402_1005Metric"
			(at 254 179.07 0)
			(effects
				(font
					(size 1.27 1.27)
					(thickness 0.15)
				)
				(justify left bottom)
				(hide yes)
			)
		)
		(property "Datasheet" "https://industrial.panasonic.com/cdbs/www-data/pdf/RDA0000/AOA0000C301.pdf"
			(at 254 176.53 0)
			(effects
				(font
					(size 1.27 1.27)
					(thickness 0.15)
				)
				(justify left bottom)
				(hide yes)
			)
		)
		(property "Description" ""
			(at 274.32 194.31 0)
			(effects
				(font
					(size 1.27 1.27)
				)
				(hide yes)
			)
		)
		(property "Manufacturer" "Panasonic"
			(at 254 171.45 0)
			(effects
				(font
					(size 1.27 1.27)
					(thickness 0.15)
				)
				(justify left bottom)
				(hide yes)
			)
		)
		(property "MPN" "ERJ2GE0R00X"
			(at 254 173.99 0)
			(effects
				(font
					(size 1.27 1.27)
					(thickness 0.15)
				)
				(justify left bottom)
				(hide yes)
			)
		)
		(property "Val" "0R"
			(at 271.78 192.405 0)
			(effects
				(font
					(size 1.27 1.27)
					(thickness 0.15)
				)
			)
		)
		(property "License" "Apache-2.0"
			(at 254 168.91 0)
			(effects
				(font
					(size 1.27 1.27)
					(thickness 0.15)
				)
				(justify left bottom)
				(hide yes)
			)
		)
		(property "Author" "Antmicro"
			(at 254 166.37 0)
			(effects
				(font
					(size 1.27 1.27)
					(thickness 0.15)
				)
				(justify left bottom)
				(hide yes)
			)
		)
		(property "Tolerance" "~"
			(at 254 184.15 0)
			(effects
				(font
					(size 1.27 1.27)
				)
				(justify left bottom)
				(hide yes)
			)
		)
		(property "Current" "1A"
			(at 274.955 193.04 0)
			(effects
				(font
					(size 1.27 1.27)
					(thickness 0.15)
				)
				(hide yes)
			)
		)
		(pin "1"
		)
		(pin "2"
		)
		(instances
			(project "cm4-baseboard"
				(path ""
					(reference "R417")
					(unit 1)
				)
			)
		)
	)
	(symbol
		(lib_id "antmicroCapacitorsmisc:C_22u_100V_2220")
		(at 238.76 194.31 90)
		(unit 1)
		(exclude_from_sim no)
		(in_bom yes)
		(on_board yes)
		(dnp no)
		(property "Reference" "C407"
			(at 239.395 194.31 90)
			(effects
				(font
					(size 1.27 1.27)
				)
				(justify right)
			)
		)
		(property "Value" "C_22u_100V_2220"
			(at 248.92 173.99 0)
			(effects
				(font
					(size 1.27 1.27)
					(thickness 0.15)
				)
				(justify left bottom)
				(hide yes)
			)
		)
		(property "Footprint" "antmicro-footprints:C_2220_5650Metric"
			(at 251.46 173.99 0)
			(effects
				(font
					(size 1.27 1.27)
					(thickness 0.15)
				)
				(justify left bottom)
				(hide yes)
			)
		)
		(property "Datasheet" "https://product.tdk.com/en/search/capacitor/ceramic/mlcc/info?part_no=C5750X7S2A226M280KB"
			(at 254 173.99 0)
			(effects
				(font
					(size 1.27 1.27)
					(thickness 0.15)
				)
				(justify left bottom)
				(hide yes)
			)
		)
		(property "Description" ""
			(at 238.76 194.31 0)
			(effects
				(font
					(size 1.27 1.27)
				)
				(hide yes)
			)
		)
		(property "Manufacturer" "TDK"
			(at 259.08 173.99 0)
			(effects
				(font
					(size 1.27 1.27)
					(thickness 0.15)
				)
				(justify left bottom)
				(hide yes)
			)
		)
		(property "MPN" "C5750X7S2A226M280KB"
			(at 256.54 173.99 0)
			(effects
				(font
					(size 1.27 1.27)
					(thickness 0.15)
				)
				(justify left bottom)
				(hide yes)
			)
		)
		(property "Val" "22u"
			(at 239.395 196.85 90)
			(effects
				(font
					(size 1.27 1.27)
					(thickness 0.15)
				)
				(justify right)
			)
		)
		(property "License" "Apache-2.0"
			(at 261.62 173.99 0)
			(effects
				(font
					(size 1.27 1.27)
					(thickness 0.15)
				)
				(justify left bottom)
				(hide yes)
			)
		)
		(property "Author" "Antmicro"
			(at 264.16 173.99 0)
			(effects
				(font
					(size 1.27 1.27)
					(thickness 0.15)
				)
				(justify left bottom)
				(hide yes)
			)
		)
		(property "Voltage" "100V"
			(at 239.395 199.39 90)
			(effects
				(font
					(size 1.27 1.27)
				)
				(justify right)
			)
		)
		(property "Dielectric" "X7S"
			(at 269.24 173.99 0)
			(effects
				(font
					(size 1.27 1.27)
				)
				(justify left bottom)
				(hide yes)
			)
		)
		(property "Public" "False"
			(at 271.78 173.99 0)
			(effects
				(font
					(size 1.27 1.27)
				)
				(justify left bottom)
				(hide yes)
			)
		)
		(pin "1"
		)
		(pin "2"
		)
		(instances
			(project "cm4-baseboard"
				(path ""
					(reference "C407")
					(unit 1)
				)
			)
		)
	)
	(symbol
		(lib_id "antmicroResistors0402:R_1k3_0402")
		(at 134.62 215.9 0)
		(unit 1)
		(exclude_from_sim no)
		(in_bom yes)
		(on_board yes)
		(dnp no)
		(property "Reference" "R401"
			(at 132.08 214.63 0)
			(effects
				(font
					(size 1.27 1.27)
				)
			)
		)
		(property "Value" "R_1k3_0402"
			(at 154.94 228.6 0)
			(effects
				(font
					(size 1.27 1.27)
					(thickness 0.15)
				)
				(justify left bottom)
				(hide yes)
			)
		)
		(property "Footprint" "antmicro-footprints:R_0402_1005Metric"
			(at 154.94 231.14 0)
			(effects
				(font
					(size 1.27 1.27)
					(thickness 0.15)
				)
				(justify left bottom)
				(hide yes)
			)
		)
		(property "Datasheet" "https://www.bourns.com/docs/product-datasheets/cr.pdf"
			(at 154.94 233.68 0)
			(effects
				(font
					(size 1.27 1.27)
					(thickness 0.15)
				)
				(justify left bottom)
				(hide yes)
			)
		)
		(property "Description" ""
			(at 134.62 215.9 0)
			(effects
				(font
					(size 1.27 1.27)
				)
				(hide yes)
			)
		)
		(property "Manufacturer" "Bourns"
			(at 154.94 238.76 0)
			(effects
				(font
					(size 1.27 1.27)
					(thickness 0.15)
				)
				(justify left bottom)
				(hide yes)
			)
		)
		(property "MPN" "CR0402-FX-1301GLF"
			(at 154.94 236.22 0)
			(effects
				(font
					(size 1.27 1.27)
					(thickness 0.15)
				)
				(justify left bottom)
				(hide yes)
			)
		)
		(property "Val" "1k3"
			(at 141.605 214.63 0)
			(effects
				(font
					(size 1.27 1.27)
					(thickness 0.15)
				)
			)
		)
		(property "License" "Apache-2.0"
			(at 154.94 241.3 0)
			(effects
				(font
					(size 1.27 1.27)
					(thickness 0.15)
				)
				(justify left bottom)
				(hide yes)
			)
		)
		(property "Author" "Antmicro"
			(at 154.94 243.84 0)
			(effects
				(font
					(size 1.27 1.27)
					(thickness 0.15)
				)
				(justify left bottom)
				(hide yes)
			)
		)
		(property "Tolerance" "1%"
			(at 154.94 226.06 0)
			(effects
				(font
					(size 1.27 1.27)
				)
				(justify left bottom)
				(hide yes)
			)
		)
		(pin "1"
		)
		(pin "2"
		)
		(instances
			(project "cm4-baseboard"
				(path ""
					(reference "R401")
					(unit 1)
				)
			)
		)
	)
	(symbol
		(lib_id "antmicropower:GNDD")
		(at 238.76 201.93 0)
		(unit 1)
		(exclude_from_sim no)
		(in_bom yes)
		(on_board yes)
		(dnp no)
		(fields_autoplaced yes)
		(property "Reference" "#PWR0409"
			(at 238.76 208.28 0)
			(effects
				(font
					(size 1.27 1.27)
				)
				(justify left bottom)
				(hide yes)
			)
		)
		(property "Value" "GNDD"
			(at 238.76 206.375 0)
			(effects
				(font
					(size 1.27 1.27)
				)
			)
		)
		(property "Footprint" ""
			(at 238.76 201.93 0)
			(effects
				(font
					(size 1.27 1.27)
				)
				(hide yes)
			)
		)
		(property "Datasheet" ""
			(at 238.76 201.93 0)
			(effects
				(font
					(size 1.27 1.27)
				)
				(hide yes)
			)
		)
		(property "Description" ""
			(at 238.76 201.93 0)
			(effects
				(font
					(size 1.27 1.27)
				)
				(hide yes)
			)
		)
		(property "Author" "Antmicro"
			(at 254 209.55 0)
			(effects
				(font
					(size 1.27 1.27)
					(thickness 0.15)
				)
				(justify left bottom)
				(hide yes)
			)
		)
		(property "License" "Apache-2.0"
			(at 254 212.09 0)
			(effects
				(font
					(size 1.27 1.27)
					(thickness 0.15)
				)
				(justify left bottom)
				(hide yes)
			)
		)
		(pin "1"
		)
		(instances
			(project "cm4-baseboard"
				(path ""
					(reference "#PWR0409")
					(unit 1)
				)
			)
		)
	)
	(symbol
		(lib_id "antmicroTestPoints:TP_0.75mm_SMD")
		(at 367.03 181.61 90)
		(unit 1)
		(exclude_from_sim no)
		(in_bom no)
		(on_board yes)
		(dnp no)
		(property "Reference" "TP403"
			(at 365.125 176.53 90)
			(effects
				(font
					(size 1.27 1.27)
				)
				(justify right)
			)
		)
		(property "Value" "TP_0.75mm_SMD"
			(at 369.57 181.61 0)
			(effects
				(font
					(size 1.27 1.27)
					(thickness 0.15)
				)
				(justify left bottom)
				(hide yes)
			)
		)
		(property "Footprint" "antmicro-footprints:TP_SMD_0.75mm"
			(at 361.95 176.53 0)
			(effects
				(font
					(size 1.27 1.27)
					(thickness 0.15)
				)
				(justify left bottom)
				(hide yes)
			)
		)
		(property "Datasheet" ""
			(at 359.41 176.53 0)
			(effects
				(font
					(size 1.27 1.27)
					(thickness 0.15)
				)
				(justify left bottom)
				(hide yes)
			)
		)
		(property "Description" ""
			(at 367.03 181.61 0)
			(effects
				(font
					(size 1.27 1.27)
				)
				(hide yes)
			)
		)
		(property "MPN" ""
			(at 367.03 181.61 0)
			(effects
				(font
					(size 1.27 1.27)
					(thickness 0.15)
				)
				(justify left bottom)
				(hide yes)
			)
		)
		(property "Manufacturer" ""
			(at 367.03 181.61 0)
			(effects
				(font
					(size 1.27 1.27)
					(thickness 0.15)
				)
				(justify left bottom)
				(hide yes)
			)
		)
		(property "Author" "Antmicro"
			(at 382.27 166.37 0)
			(effects
				(font
					(size 1.27 1.27)
					(thickness 0.15)
				)
				(justify left bottom)
				(hide yes)
			)
		)
		(property "License" "Apache-2.0"
			(at 384.81 166.37 0)
			(effects
				(font
					(size 1.27 1.27)
					(thickness 0.15)
				)
				(justify left bottom)
				(hide yes)
			)
		)
		(pin "1"
		)
		(instances
			(project "cm4-baseboard"
				(path ""
					(reference "TP403")
					(unit 1)
				)
			)
		)
	)
	(symbol
		(lib_id "antmicroResistors0402:R_470R_0402")
		(at 279.4 236.22 0)
		(unit 1)
		(exclude_from_sim no)
		(in_bom yes)
		(on_board yes)
		(dnp no)
		(property "Reference" "R418"
			(at 281.94 234.315 0)
			(effects
				(font
					(size 1.27 1.27)
				)
			)
		)
		(property "Value" "R_470R_0402"
			(at 299.72 248.92 0)
			(effects
				(font
					(size 1.27 1.27)
					(thickness 0.15)
				)
				(justify left bottom)
				(hide yes)
			)
		)
		(property "Footprint" "antmicro-footprints:R_0402_1005Metric"
			(at 299.72 251.46 0)
			(effects
				(font
					(size 1.27 1.27)
					(thickness 0.15)
				)
				(justify left bottom)
				(hide yes)
			)
		)
		(property "Datasheet" "https://www.bourns.com/docs/product-datasheets/cr.pdf"
			(at 299.72 254 0)
			(effects
				(font
					(size 1.27 1.27)
					(thickness 0.15)
				)
				(justify left bottom)
				(hide yes)
			)
		)
		(property "Description" ""
			(at 279.4 236.22 0)
			(effects
				(font
					(size 1.27 1.27)
				)
				(hide yes)
			)
		)
		(property "Manufacturer" "Bourns"
			(at 299.72 259.08 0)
			(effects
				(font
					(size 1.27 1.27)
					(thickness 0.15)
				)
				(justify left bottom)
				(hide yes)
			)
		)
		(property "MPN" "CR0402-FX-4700GLF"
			(at 299.72 256.54 0)
			(effects
				(font
					(size 1.27 1.27)
					(thickness 0.15)
				)
				(justify left bottom)
				(hide yes)
			)
		)
		(property "Val" "470R"
			(at 281.94 238.125 0)
			(effects
				(font
					(size 1.27 1.27)
					(thickness 0.15)
				)
			)
		)
		(property "License" "Apache-2.0"
			(at 299.72 261.62 0)
			(effects
				(font
					(size 1.27 1.27)
					(thickness 0.15)
				)
				(justify left bottom)
				(hide yes)
			)
		)
		(property "Author" "Antmicro"
			(at 299.72 264.16 0)
			(effects
				(font
					(size 1.27 1.27)
					(thickness 0.15)
				)
				(justify left bottom)
				(hide yes)
			)
		)
		(property "Tolerance" "1%"
			(at 299.72 246.38 0)
			(effects
				(font
					(size 1.27 1.27)
				)
				(justify left bottom)
				(hide yes)
			)
		)
		(pin "1"
		)
		(pin "2"
		)
		(instances
			(project "cm4-baseboard"
				(path ""
					(reference "R418")
					(unit 1)
				)
			)
		)
	)
	(symbol
		(lib_id "antmicropower:GNDD")
		(at 266.7 217.17 0)
		(unit 1)
		(exclude_from_sim no)
		(in_bom yes)
		(on_board yes)
		(dnp no)
		(fields_autoplaced yes)
		(property "Reference" "#PWR0411"
			(at 266.7 223.52 0)
			(effects
				(font
					(size 1.27 1.27)
				)
				(justify left bottom)
				(hide yes)
			)
		)
		(property "Value" "GNDD"
			(at 266.7 221.615 0)
			(effects
				(font
					(size 1.27 1.27)
				)
			)
		)
		(property "Footprint" ""
			(at 266.7 217.17 0)
			(effects
				(font
					(size 1.27 1.27)
				)
				(hide yes)
			)
		)
		(property "Datasheet" ""
			(at 266.7 217.17 0)
			(effects
				(font
					(size 1.27 1.27)
				)
				(hide yes)
			)
		)
		(property "Description" ""
			(at 266.7 217.17 0)
			(effects
				(font
					(size 1.27 1.27)
				)
				(hide yes)
			)
		)
		(property "Author" "Antmicro"
			(at 281.94 224.79 0)
			(effects
				(font
					(size 1.27 1.27)
					(thickness 0.15)
				)
				(justify left bottom)
				(hide yes)
			)
		)
		(property "License" "Apache-2.0"
			(at 281.94 227.33 0)
			(effects
				(font
					(size 1.27 1.27)
					(thickness 0.15)
				)
				(justify left bottom)
				(hide yes)
			)
		)
		(pin "1"
		)
		(instances
			(project "cm4-baseboard"
				(path ""
					(reference "#PWR0411")
					(unit 1)
				)
			)
		)
	)
	(symbol
		(lib_id "antmicroResistors0402:R_0R_0402")
		(at 139.7 220.98 180)
		(unit 1)
		(exclude_from_sim no)
		(in_bom yes)
		(on_board yes)
		(dnp no)
		(property "Reference" "R403"
			(at 132.08 219.71 0)
			(effects
				(font
					(size 1.27 1.27)
				)
			)
		)
		(property "Value" "R_0R_0402"
			(at 119.38 208.28 0)
			(effects
				(font
					(size 1.27 1.27)
					(thickness 0.15)
				)
				(justify left bottom)
				(hide yes)
			)
		)
		(property "Footprint" "antmicro-footprints:R_0402_1005Metric"
			(at 119.38 205.74 0)
			(effects
				(font
					(size 1.27 1.27)
					(thickness 0.15)
				)
				(justify left bottom)
				(hide yes)
			)
		)
		(property "Datasheet" "https://industrial.panasonic.com/cdbs/www-data/pdf/RDA0000/AOA0000C301.pdf"
			(at 119.38 203.2 0)
			(effects
				(font
					(size 1.27 1.27)
					(thickness 0.15)
				)
				(justify left bottom)
				(hide yes)
			)
		)
		(property "Description" ""
			(at 139.7 220.98 0)
			(effects
				(font
					(size 1.27 1.27)
				)
				(hide yes)
			)
		)
		(property "Manufacturer" "Panasonic"
			(at 119.38 198.12 0)
			(effects
				(font
					(size 1.27 1.27)
					(thickness 0.15)
				)
				(justify left bottom)
				(hide yes)
			)
		)
		(property "MPN" "ERJ2GE0R00X"
			(at 119.38 200.66 0)
			(effects
				(font
					(size 1.27 1.27)
					(thickness 0.15)
				)
				(justify left bottom)
				(hide yes)
			)
		)
		(property "Val" "0R"
			(at 140.97 219.71 0)
			(effects
				(font
					(size 1.27 1.27)
					(thickness 0.15)
				)
			)
		)
		(property "License" "Apache-2.0"
			(at 119.38 195.58 0)
			(effects
				(font
					(size 1.27 1.27)
					(thickness 0.15)
				)
				(justify left bottom)
				(hide yes)
			)
		)
		(property "Author" "Antmicro"
			(at 119.38 193.04 0)
			(effects
				(font
					(size 1.27 1.27)
					(thickness 0.15)
				)
				(justify left bottom)
				(hide yes)
			)
		)
		(property "Tolerance" "~"
			(at 119.38 210.82 0)
			(effects
				(font
					(size 1.27 1.27)
				)
				(justify left bottom)
				(hide yes)
			)
		)
		(property "Current" "1A"
			(at 137.16 220.98 0)
			(effects
				(font
					(size 1.27 1.27)
					(thickness 0.15)
				)
				(hide yes)
			)
		)
		(pin "1"
		)
		(pin "2"
		)
		(instances
			(project "cm4-baseboard"
				(path ""
					(reference "R403")
					(unit 1)
				)
			)
		)
	)
	(symbol
		(lib_id "antmicroCapacitorsmisc:C_22u_25V_0805")
		(at 349.25 187.96 90)
		(mirror x)
		(unit 1)
		(exclude_from_sim no)
		(in_bom yes)
		(on_board yes)
		(dnp no)
		(property "Reference" "C409"
			(at 350.52 191.77 90)
			(effects
				(font
					(size 1.27 1.27)
				)
				(justify right)
			)
		)
		(property "Value" "C_22u_25V_0805"
			(at 353.06 187.96 0)
			(effects
				(font
					(size 1.27 1.27)
				)
				(justify left bottom)
				(hide yes)
			)
		)
		(property "Footprint" "antmicro-footprints:C_0805_2012Metric"
			(at 344.17 193.04 0)
			(effects
				(font
					(size 1.524 1.524)
				)
				(justify left bottom)
				(hide yes)
			)
		)
		(property "Datasheet" "https://product.samsungsem.com/mlcc/CL21A226MAYNNN.do"
			(at 349.25 187.96 0)
			(effects
				(font
					(size 1.27 1.27)
				)
				(justify left bottom)
				(hide yes)
			)
		)
		(property "Description" ""
			(at 349.25 187.96 0)
			(effects
				(font
					(size 1.27 1.27)
				)
				(hide yes)
			)
		)
		(property "Manufacturer" "Samsung Electro-Mechanics"
			(at 339.09 193.04 0)
			(effects
				(font
					(size 1.524 1.524)
				)
				(justify left bottom)
				(hide yes)
			)
		)
		(property "MPN" "CL21A226MAYNNNE"
			(at 341.63 193.04 0)
			(effects
				(font
					(size 1.524 1.524)
				)
				(justify left bottom)
				(hide yes)
			)
		)
		(property "Val" "22u"
			(at 350.52 194.31 90)
			(effects
				(font
					(size 1.27 1.27)
				)
				(justify right)
			)
		)
		(property "License" "Apache-2.0"
			(at 372.11 208.28 0)
			(effects
				(font
					(size 1.27 1.27)
					(thickness 0.15)
				)
				(justify left bottom)
				(hide yes)
			)
		)
		(property "Author" "Antmicro"
			(at 374.65 208.28 0)
			(effects
				(font
					(size 1.27 1.27)
					(thickness 0.15)
				)
				(justify left bottom)
				(hide yes)
			)
		)
		(property "Voltage" "25V"
			(at 350.52 196.85 90)
			(effects
				(font
					(size 1.27 1.27)
				)
				(justify right)
			)
		)
		(property "Dielectric" "X5R"
			(at 379.73 208.28 0)
			(effects
				(font
					(size 1.27 1.27)
				)
				(justify left bottom)
				(hide yes)
			)
		)
		(property "Public" "False"
			(at 382.27 208.28 0)
			(effects
				(font
					(size 1.27 1.27)
				)
				(justify left bottom)
				(hide yes)
			)
		)
		(pin "1"
		)
		(pin "2"
		)
		(instances
			(project "cm4-baseboard"
				(path ""
					(reference "C409")
					(unit 1)
				)
			)
		)
	)
	(symbol
		(lib_id "antmicroCapacitors0402:C_100n_0402")
		(at 367.03 187.96 90)
		(mirror x)
		(unit 1)
		(exclude_from_sim no)
		(in_bom yes)
		(on_board yes)
		(dnp no)
		(property "Reference" "C411"
			(at 368.935 191.77 90)
			(effects
				(font
					(size 1.27 1.27)
				)
				(justify right)
			)
		)
		(property "Value" "C_100n_0402"
			(at 377.19 208.28 0)
			(effects
				(font
					(size 1.27 1.27)
					(thickness 0.15)
				)
				(justify left bottom)
				(hide yes)
			)
		)
		(property "Footprint" "antmicro-footprints:C_0402_1005Metric"
			(at 379.73 208.28 0)
			(effects
				(font
					(size 1.27 1.27)
					(thickness 0.15)
				)
				(justify left bottom)
				(hide yes)
			)
		)
		(property "Datasheet" "https://www.murata.com/products/productdetail?partno=GRM155R61H104KE14%23"
			(at 382.27 208.28 0)
			(effects
				(font
					(size 1.27 1.27)
					(thickness 0.15)
				)
				(justify left bottom)
				(hide yes)
			)
		)
		(property "Description" ""
			(at 367.03 187.96 0)
			(effects
				(font
					(size 1.27 1.27)
				)
				(hide yes)
			)
		)
		(property "MPN" "GRM155R61H104KE14D"
			(at 384.81 208.28 0)
			(effects
				(font
					(size 1.27 1.27)
					(thickness 0.15)
				)
				(justify left bottom)
				(hide yes)
			)
		)
		(property "Manufacturer" "Murata"
			(at 387.35 208.28 0)
			(effects
				(font
					(size 1.27 1.27)
					(thickness 0.15)
				)
				(justify left bottom)
				(hide yes)
			)
		)
		(property "Val" "100n"
			(at 368.935 194.31 90)
			(effects
				(font
					(size 1.27 1.27)
					(thickness 0.15)
				)
				(justify right)
			)
		)
		(property "License" "Apache-2.0"
			(at 389.89 208.28 0)
			(effects
				(font
					(size 1.27 1.27)
					(thickness 0.15)
				)
				(justify left bottom)
				(hide yes)
			)
		)
		(property "Author" "Antmicro"
			(at 392.43 208.28 0)
			(effects
				(font
					(size 1.27 1.27)
					(thickness 0.15)
				)
				(justify left bottom)
				(hide yes)
			)
		)
		(property "Voltage" "50V"
			(at 394.97 208.28 0)
			(effects
				(font
					(size 1.27 1.27)
				)
				(justify left bottom)
				(hide yes)
			)
		)
		(property "Dielectric" "X5R"
			(at 397.51 208.28 0)
			(effects
				(font
					(size 1.27 1.27)
				)
				(justify left bottom)
				(hide yes)
			)
		)
		(pin "1"
		)
		(pin "2"
		)
		(instances
			(project "cm4-baseboard"
				(path ""
					(reference "C411")
					(unit 1)
				)
			)
		)
	)
	(symbol
		(lib_id "antmicropower:GND")
		(at 181.61 95.25 0)
		(unit 1)
		(exclude_from_sim no)
		(in_bom yes)
		(on_board yes)
		(dnp no)
		(fields_autoplaced yes)
		(property "Reference" "#PWR0402"
			(at 181.61 101.6 0)
			(effects
				(font
					(size 1.27 1.27)
				)
				(justify left bottom)
				(hide yes)
			)
		)
		(property "Value" "GND"
			(at 181.61 100.33 0)
			(effects
				(font
					(size 1.27 1.27)
				)
			)
		)
		(property "Footprint" ""
			(at 190.5 102.87 0)
			(effects
				(font
					(size 1.27 1.27)
					(thickness 0.15)
				)
				(justify left bottom)
				(hide yes)
			)
		)
		(property "Datasheet" ""
			(at 190.5 107.95 0)
			(effects
				(font
					(size 1.27 1.27)
					(thickness 0.15)
				)
				(justify left bottom)
				(hide yes)
			)
		)
		(property "Description" ""
			(at 181.61 95.25 0)
			(effects
				(font
					(size 1.27 1.27)
				)
				(hide yes)
			)
		)
		(property "Author" "Antmicro"
			(at 190.5 102.87 0)
			(effects
				(font
					(size 1.27 1.27)
					(thickness 0.15)
				)
				(justify left bottom)
				(hide yes)
			)
		)
		(property "License" "Apache-2.0"
			(at 190.5 105.41 0)
			(effects
				(font
					(size 1.27 1.27)
					(thickness 0.15)
				)
				(justify left bottom)
				(hide yes)
			)
		)
		(pin "1"
		)
		(instances
			(project "cm4-baseboard"
				(path ""
					(reference "#PWR0402")
					(unit 1)
				)
			)
		)
	)
	(symbol
		(lib_id "antmicropower:+3V3")
		(at 208.28 71.12 0)
		(unit 1)
		(exclude_from_sim no)
		(in_bom yes)
		(on_board yes)
		(dnp no)
		(fields_autoplaced yes)
		(property "Reference" "#PWR0403"
			(at 223.52 73.66 0)
			(effects
				(font
					(size 1.27 1.27)
					(thickness 0.15)
				)
				(justify left bottom)
				(hide yes)
			)
		)
		(property "Value" "+3V3"
			(at 208.28 66.04 0)
			(effects
				(font
					(size 1.27 1.27)
					(thickness 0.15)
				)
			)
		)
		(property "Footprint" ""
			(at 223.52 78.74 0)
			(effects
				(font
					(size 1.27 1.27)
					(thickness 0.15)
				)
				(justify left bottom)
				(hide yes)
			)
		)
		(property "Datasheet" ""
			(at 223.52 81.28 0)
			(effects
				(font
					(size 1.27 1.27)
					(thickness 0.15)
				)
				(justify left bottom)
				(hide yes)
			)
		)
		(property "Description" ""
			(at 208.28 71.12 0)
			(effects
				(font
					(size 1.27 1.27)
				)
				(hide yes)
			)
		)
		(property "Author" "Antmicro"
			(at 223.52 78.74 0)
			(effects
				(font
					(size 1.27 1.27)
					(thickness 0.15)
				)
				(justify left bottom)
				(hide yes)
			)
		)
		(property "License" "Apache-2.0"
			(at 223.52 81.28 0)
			(effects
				(font
					(size 1.27 1.27)
					(thickness 0.15)
				)
				(justify left bottom)
				(hide yes)
			)
		)
		(pin "1"
		)
		(instances
			(project "cm4-baseboard"
				(path ""
					(reference "#PWR0403")
					(unit 1)
				)
			)
		)
	)
	(symbol
		(lib_id "antmicroFerriteBeadsandChips:FB_220Z_2.2A_TDK-MPZ_0603")
		(at 97.79 213.36 0)
		(unit 1)
		(exclude_from_sim no)
		(in_bom yes)
		(on_board yes)
		(dnp no)
		(fields_autoplaced yes)
		(property "Reference" "FB402"
			(at 100.2919 207.01 0)
			(effects
				(font
					(size 1.27 1.27)
				)
			)
		)
		(property "Value" "FB_220Z_2.2A_TDK-MPZ_0603"
			(at 100.2919 219.71 0)
			(effects
				(font
					(size 1.27 1.27)
					(thickness 0.15)
				)
				(hide yes)
			)
		)
		(property "Footprint" "antmicro-footprints:FB_0603_1608Metric"
			(at 111.76 218.44 0)
			(effects
				(font
					(size 1.27 1.27)
					(thickness 0.15)
				)
				(justify left bottom)
				(hide yes)
			)
		)
		(property "Datasheet" "https://product.tdk.com/info/en/catalog/datasheets/beads_commercial_power_mpz1608_en.pdf"
			(at 111.76 220.98 0)
			(effects
				(font
					(size 1.27 1.27)
					(thickness 0.15)
				)
				(justify left bottom)
				(hide yes)
			)
		)
		(property "Description" ""
			(at 97.79 213.36 0)
			(effects
				(font
					(size 1.27 1.27)
				)
				(hide yes)
			)
		)
		(property "MPN" "MPZ1608S221ATA00"
			(at 111.76 223.52 0)
			(effects
				(font
					(size 1.27 1.27)
					(thickness 0.15)
				)
				(justify left bottom)
				(hide yes)
			)
		)
		(property "Manufacturer" "TDK"
			(at 111.76 226.06 0)
			(effects
				(font
					(size 1.27 1.27)
					(thickness 0.15)
				)
				(justify left bottom)
				(hide yes)
			)
		)
		(property "Author" "Antmicro"
			(at 111.76 228.6 0)
			(effects
				(font
					(size 1.27 1.27)
					(thickness 0.15)
				)
				(justify left bottom)
				(hide yes)
			)
		)
		(property "License" "Apache-2.0"
			(at 111.76 231.14 0)
			(effects
				(font
					(size 1.27 1.27)
					(thickness 0.15)
				)
				(justify left bottom)
				(hide yes)
			)
		)
		(property "Val" "220Z/2.2A"
			(at 100.2919 209.55 0)
			(effects
				(font
					(size 1.27 1.27)
				)
			)
		)
		(property "Current" ""
			(at 0 426.72 0)
			(effects
				(font
					(size 1.27 1.27)
				)
				(hide yes)
			)
		)
		(pin "1"
		)
		(pin "2"
		)
		(instances
			(project "cm4-baseboard"
				(path ""
					(reference "FB402")
					(unit 1)
				)
			)
		)
	)
	(symbol
		(lib_id "antmicropower:GNDD")
		(at 299.72 217.17 0)
		(unit 1)
		(exclude_from_sim no)
		(in_bom yes)
		(on_board yes)
		(dnp no)
		(fields_autoplaced yes)
		(property "Reference" "#PWR0418"
			(at 299.72 223.52 0)
			(effects
				(font
					(size 1.27 1.27)
				)
				(justify left bottom)
				(hide yes)
			)
		)
		(property "Value" "GNDD"
			(at 299.72 222.25 0)
			(effects
				(font
					(size 1.27 1.27)
				)
			)
		)
		(property "Footprint" ""
			(at 299.72 217.17 0)
			(effects
				(font
					(size 1.27 1.27)
				)
				(hide yes)
			)
		)
		(property "Datasheet" ""
			(at 299.72 217.17 0)
			(effects
				(font
					(size 1.27 1.27)
				)
				(hide yes)
			)
		)
		(property "Description" ""
			(at 299.72 217.17 0)
			(effects
				(font
					(size 1.27 1.27)
				)
				(hide yes)
			)
		)
		(property "Author" "Antmicro"
			(at 314.96 224.79 0)
			(effects
				(font
					(size 1.27 1.27)
					(thickness 0.15)
				)
				(justify left bottom)
				(hide yes)
			)
		)
		(property "License" "Apache-2.0"
			(at 314.96 227.33 0)
			(effects
				(font
					(size 1.27 1.27)
					(thickness 0.15)
				)
				(justify left bottom)
				(hide yes)
			)
		)
		(pin "1"
		)
		(instances
			(project "cm4-baseboard"
				(path ""
					(reference "#PWR0418")
					(unit 1)
				)
			)
		)
	)
	(symbol
		(lib_id "antmicroCapacitorsmisc:C_22u_100V_2220")
		(at 224.79 194.31 90)
		(unit 1)
		(exclude_from_sim no)
		(in_bom yes)
		(on_board yes)
		(dnp no)
		(property "Reference" "C405"
			(at 225.425 194.31 90)
			(effects
				(font
					(size 1.27 1.27)
				)
				(justify right)
			)
		)
		(property "Value" "C_22u_100V_2220"
			(at 234.95 173.99 0)
			(effects
				(font
					(size 1.27 1.27)
					(thickness 0.15)
				)
				(justify left bottom)
				(hide yes)
			)
		)
		(property "Footprint" "antmicro-footprints:C_2220_5650Metric"
			(at 237.49 173.99 0)
			(effects
				(font
					(size 1.27 1.27)
					(thickness 0.15)
				)
				(justify left bottom)
				(hide yes)
			)
		)
		(property "Datasheet" "https://product.tdk.com/en/search/capacitor/ceramic/mlcc/info?part_no=C5750X7S2A226M280KB"
			(at 240.03 173.99 0)
			(effects
				(font
					(size 1.27 1.27)
					(thickness 0.15)
				)
				(justify left bottom)
				(hide yes)
			)
		)
		(property "Description" ""
			(at 224.79 194.31 0)
			(effects
				(font
					(size 1.27 1.27)
				)
				(hide yes)
			)
		)
		(property "Manufacturer" "TDK"
			(at 245.11 173.99 0)
			(effects
				(font
					(size 1.27 1.27)
					(thickness 0.15)
				)
				(justify left bottom)
				(hide yes)
			)
		)
		(property "MPN" "C5750X7S2A226M280KB"
			(at 242.57 173.99 0)
			(effects
				(font
					(size 1.27 1.27)
					(thickness 0.15)
				)
				(justify left bottom)
				(hide yes)
			)
		)
		(property "Val" "22u"
			(at 225.425 196.85 90)
			(effects
				(font
					(size 1.27 1.27)
					(thickness 0.15)
				)
				(justify right)
			)
		)
		(property "License" "Apache-2.0"
			(at 247.65 173.99 0)
			(effects
				(font
					(size 1.27 1.27)
					(thickness 0.15)
				)
				(justify left bottom)
				(hide yes)
			)
		)
		(property "Author" "Antmicro"
			(at 250.19 173.99 0)
			(effects
				(font
					(size 1.27 1.27)
					(thickness 0.15)
				)
				(justify left bottom)
				(hide yes)
			)
		)
		(property "Voltage" "100V"
			(at 225.425 199.39 90)
			(effects
				(font
					(size 1.27 1.27)
				)
				(justify right)
			)
		)
		(property "Dielectric" "X7S"
			(at 255.27 173.99 0)
			(effects
				(font
					(size 1.27 1.27)
				)
				(justify left bottom)
				(hide yes)
			)
		)
		(property "Public" "False"
			(at 257.81 173.99 0)
			(effects
				(font
					(size 1.27 1.27)
				)
				(justify left bottom)
				(hide yes)
			)
		)
		(pin "1"
		)
		(pin "2"
		)
		(instances
			(project "cm4-baseboard"
				(path ""
					(reference "C405")
					(unit 1)
				)
			)
		)
	)
	(symbol
		(lib_id "antmicropower:GNDD")
		(at 179.07 234.95 0)
		(unit 1)
		(exclude_from_sim no)
		(in_bom yes)
		(on_board yes)
		(dnp no)
		(property "Reference" "#PWR0401"
			(at 179.07 241.3 0)
			(effects
				(font
					(size 1.27 1.27)
				)
				(justify left bottom)
				(hide yes)
			)
		)
		(property "Value" "GNDD"
			(at 176.53 238.76 0)
			(effects
				(font
					(size 1.27 1.27)
				)
				(justify left)
			)
		)
		(property "Footprint" ""
			(at 179.07 234.95 0)
			(effects
				(font
					(size 1.27 1.27)
				)
				(hide yes)
			)
		)
		(property "Datasheet" ""
			(at 179.07 234.95 0)
			(effects
				(font
					(size 1.27 1.27)
				)
				(hide yes)
			)
		)
		(property "Description" ""
			(at 179.07 234.95 0)
			(effects
				(font
					(size 1.27 1.27)
				)
				(hide yes)
			)
		)
		(property "Author" "Antmicro"
			(at 194.31 242.57 0)
			(effects
				(font
					(size 1.27 1.27)
					(thickness 0.15)
				)
				(justify left bottom)
				(hide yes)
			)
		)
		(property "License" "Apache-2.0"
			(at 194.31 245.11 0)
			(effects
				(font
					(size 1.27 1.27)
					(thickness 0.15)
				)
				(justify left bottom)
				(hide yes)
			)
		)
		(pin "1"
		)
		(instances
			(project "cm4-baseboard"
				(path ""
					(reference "#PWR0401")
					(unit 1)
				)
			)
		)
	)
	(symbol
		(lib_id "antmicropower:GNDD")
		(at 247.65 201.93 0)
		(unit 1)
		(exclude_from_sim no)
		(in_bom yes)
		(on_board yes)
		(dnp no)
		(property "Reference" "#PWR0410"
			(at 247.65 208.28 0)
			(effects
				(font
					(size 1.27 1.27)
				)
				(justify left bottom)
				(hide yes)
			)
		)
		(property "Value" "GNDD"
			(at 247.65 207.01 0)
			(effects
				(font
					(size 1.27 1.27)
				)
			)
		)
		(property "Footprint" ""
			(at 247.65 201.93 0)
			(effects
				(font
					(size 1.27 1.27)
				)
				(hide yes)
			)
		)
		(property "Datasheet" ""
			(at 247.65 201.93 0)
			(effects
				(font
					(size 1.27 1.27)
				)
				(hide yes)
			)
		)
		(property "Description" ""
			(at 247.65 201.93 0)
			(effects
				(font
					(size 1.27 1.27)
				)
				(hide yes)
			)
		)
		(property "Author" "Antmicro"
			(at 262.89 209.55 0)
			(effects
				(font
					(size 1.27 1.27)
					(thickness 0.15)
				)
				(justify left bottom)
				(hide yes)
			)
		)
		(property "License" "Apache-2.0"
			(at 262.89 212.09 0)
			(effects
				(font
					(size 1.27 1.27)
					(thickness 0.15)
				)
				(justify left bottom)
				(hide yes)
			)
		)
		(pin "1"
		)
		(instances
			(project "cm4-baseboard"
				(path ""
					(reference "#PWR0410")
					(unit 1)
				)
			)
		)
	)
	(symbol
		(lib_id "antmicroDiodesRectifiersSingle:CD-MMBL110S")
		(at 69.85 198.12 0)
		(unit 1)
		(exclude_from_sim no)
		(in_bom yes)
		(on_board yes)
		(dnp no)
		(property "Reference" "D402"
			(at 78.74 193.04 0)
			(effects
				(font
					(size 1.27 1.27)
				)
			)
		)
		(property "Value" "CD-MMBL110S"
			(at 78.74 195.58 0)
			(effects
				(font
					(size 1.27 1.27)
					(thickness 0.15)
				)
			)
		)
		(property "Footprint" "antmicro-footprints:DFN3538"
			(at 101.6 208.28 0)
			(effects
				(font
					(size 1.27 1.27)
					(thickness 0.15)
				)
				(justify left bottom)
				(hide yes)
			)
		)
		(property "Datasheet" "https://www.bourns.com/docs/product-datasheets/CD-MMBL110S.pdf"
			(at 101.6 210.82 0)
			(effects
				(font
					(size 1.27 1.27)
					(thickness 0.15)
				)
				(justify left bottom)
				(hide yes)
			)
		)
		(property "Description" ""
			(at 69.85 198.12 0)
			(effects
				(font
					(size 1.27 1.27)
				)
				(hide yes)
			)
		)
		(property "MPN" "CD-MMBL110S"
			(at 101.6 213.36 0)
			(effects
				(font
					(size 1.27 1.27)
					(thickness 0.15)
				)
				(justify left bottom)
				(hide yes)
			)
		)
		(property "Manufacturer" "Bourns"
			(at 101.6 215.9 0)
			(effects
				(font
					(size 1.27 1.27)
					(thickness 0.15)
				)
				(justify left bottom)
				(hide yes)
			)
		)
		(property "Author" "Antmicro"
			(at 101.6 218.44 0)
			(effects
				(font
					(size 1.27 1.27)
					(thickness 0.15)
				)
				(justify left bottom)
				(hide yes)
			)
		)
		(property "License" "Apache-2.0"
			(at 101.6 220.98 0)
			(effects
				(font
					(size 1.27 1.27)
					(thickness 0.15)
				)
				(justify left bottom)
				(hide yes)
			)
		)
		(pin "1"
		)
		(pin "2"
		)
		(pin "3"
		)
		(pin "4"
		)
		(instances
			(project "cm4-baseboard"
				(path ""
					(reference "D402")
					(unit 1)
				)
			)
		)
	)
	(symbol
		(lib_id "antmicroResistors0402:R_1k2_0402")
		(at 143.51 209.55 90)
		(unit 1)
		(exclude_from_sim no)
		(in_bom yes)
		(on_board yes)
		(dnp no)
		(fields_autoplaced yes)
		(property "Reference" "R405"
			(at 146.05 205.7399 90)
			(effects
				(font
					(size 1.27 1.27)
				)
				(justify right)
			)
		)
		(property "Value" "R_1k2_0402"
			(at 156.21 189.23 0)
			(effects
				(font
					(size 1.27 1.27)
					(thickness 0.15)
				)
				(justify left bottom)
				(hide yes)
			)
		)
		(property "Footprint" "antmicro-footprints:R_0402_1005Metric"
			(at 158.75 189.23 0)
			(effects
				(font
					(size 1.27 1.27)
					(thickness 0.15)
				)
				(justify left bottom)
				(hide yes)
			)
		)
		(property "Datasheet" "https://www.bourns.com/docs/product-datasheets/cr.pdf"
			(at 161.29 189.23 0)
			(effects
				(font
					(size 1.27 1.27)
					(thickness 0.15)
				)
				(justify left bottom)
				(hide yes)
			)
		)
		(property "Description" ""
			(at 143.51 209.55 0)
			(effects
				(font
					(size 1.27 1.27)
				)
				(hide yes)
			)
		)
		(property "Manufacturer" "Bourns"
			(at 166.37 189.23 0)
			(effects
				(font
					(size 1.27 1.27)
					(thickness 0.15)
				)
				(justify left bottom)
				(hide yes)
			)
		)
		(property "MPN" "CR0402-FX-1201GLF"
			(at 163.83 189.23 0)
			(effects
				(font
					(size 1.27 1.27)
					(thickness 0.15)
				)
				(justify left bottom)
				(hide yes)
			)
		)
		(property "Val" "1k2"
			(at 146.05 208.2799 90)
			(effects
				(font
					(size 1.27 1.27)
					(thickness 0.15)
				)
				(justify right)
			)
		)
		(property "License" "Apache-2.0"
			(at 168.91 189.23 0)
			(effects
				(font
					(size 1.27 1.27)
					(thickness 0.15)
				)
				(justify left bottom)
				(hide yes)
			)
		)
		(property "Author" "Antmicro"
			(at 171.45 189.23 0)
			(effects
				(font
					(size 1.27 1.27)
					(thickness 0.15)
				)
				(justify left bottom)
				(hide yes)
			)
		)
		(property "Tolerance" "1%"
			(at 153.67 189.23 0)
			(effects
				(font
					(size 1.27 1.27)
				)
				(justify left bottom)
				(hide yes)
			)
		)
		(pin "1"
		)
		(pin "2"
		)
		(instances
			(project "cm4-baseboard"
				(path ""
					(reference "R405")
					(unit 1)
				)
			)
		)
	)
	(symbol
		(lib_id "antmicroResistors0402:R_49k9_0402")
		(at 134.62 218.44 0)
		(unit 1)
		(exclude_from_sim no)
		(in_bom yes)
		(on_board yes)
		(dnp no)
		(property "Reference" "R402"
			(at 132.08 217.17 0)
			(effects
				(font
					(size 1.27 1.27)
				)
			)
		)
		(property "Value" "R_49k9_0402"
			(at 154.94 231.14 0)
			(effects
				(font
					(size 1.27 1.27)
					(thickness 0.15)
				)
				(justify left bottom)
				(hide yes)
			)
		)
		(property "Footprint" "antmicro-footprints:R_0402_1005Metric"
			(at 154.94 233.68 0)
			(effects
				(font
					(size 1.27 1.27)
					(thickness 0.15)
				)
				(justify left bottom)
				(hide yes)
			)
		)
		(property "Datasheet" "https://www.bourns.com/docs/product-datasheets/cr.pdf"
			(at 154.94 236.22 0)
			(effects
				(font
					(size 1.27 1.27)
					(thickness 0.15)
				)
				(justify left bottom)
				(hide yes)
			)
		)
		(property "Description" ""
			(at 134.62 218.44 0)
			(effects
				(font
					(size 1.27 1.27)
				)
				(hide yes)
			)
		)
		(property "Manufacturer" "Bourns"
			(at 154.94 241.3 0)
			(effects
				(font
					(size 1.27 1.27)
					(thickness 0.15)
				)
				(justify left bottom)
				(hide yes)
			)
		)
		(property "MPN" "CR0402-FX-4992GLF"
			(at 154.94 238.76 0)
			(effects
				(font
					(size 1.27 1.27)
					(thickness 0.15)
				)
				(justify left bottom)
				(hide yes)
			)
		)
		(property "Val" "49k9"
			(at 142.24 217.17 0)
			(effects
				(font
					(size 1.27 1.27)
					(thickness 0.15)
				)
			)
		)
		(property "License" "Apache-2.0"
			(at 154.94 243.84 0)
			(effects
				(font
					(size 1.27 1.27)
					(thickness 0.15)
				)
				(justify left bottom)
				(hide yes)
			)
		)
		(property "Author" "Antmicro"
			(at 154.94 246.38 0)
			(effects
				(font
					(size 1.27 1.27)
					(thickness 0.15)
				)
				(justify left bottom)
				(hide yes)
			)
		)
		(property "Tolerance" "1%"
			(at 154.94 228.6 0)
			(effects
				(font
					(size 1.27 1.27)
				)
				(justify left bottom)
				(hide yes)
			)
		)
		(pin "1"
		)
		(pin "2"
		)
		(instances
			(project "cm4-baseboard"
				(path ""
					(reference "R402")
					(unit 1)
				)
			)
		)
	)
	(symbol
		(lib_id "antmicropower:GNDD")
		(at 275.59 217.17 0)
		(unit 1)
		(exclude_from_sim no)
		(in_bom yes)
		(on_board yes)
		(dnp no)
		(fields_autoplaced yes)
		(property "Reference" "#PWR0412"
			(at 275.59 223.52 0)
			(effects
				(font
					(size 1.27 1.27)
				)
				(justify left bottom)
				(hide yes)
			)
		)
		(property "Value" "GNDD"
			(at 275.59 221.615 0)
			(effects
				(font
					(size 1.27 1.27)
				)
			)
		)
		(property "Footprint" ""
			(at 275.59 217.17 0)
			(effects
				(font
					(size 1.27 1.27)
				)
				(hide yes)
			)
		)
		(property "Datasheet" ""
			(at 275.59 217.17 0)
			(effects
				(font
					(size 1.27 1.27)
				)
				(hide yes)
			)
		)
		(property "Description" ""
			(at 275.59 217.17 0)
			(effects
				(font
					(size 1.27 1.27)
				)
				(hide yes)
			)
		)
		(property "Author" "Antmicro"
			(at 290.83 224.79 0)
			(effects
				(font
					(size 1.27 1.27)
					(thickness 0.15)
				)
				(justify left bottom)
				(hide yes)
			)
		)
		(property "License" "Apache-2.0"
			(at 290.83 227.33 0)
			(effects
				(font
					(size 1.27 1.27)
					(thickness 0.15)
				)
				(justify left bottom)
				(hide yes)
			)
		)
		(pin "1"
		)
		(instances
			(project "cm4-baseboard"
				(path ""
					(reference "#PWR0412")
					(unit 1)
				)
			)
		)
	)
	(symbol
		(lib_id "antmicropower:PWR_FLAG")
		(at 128.27 212.09 0)
		(unit 1)
		(exclude_from_sim no)
		(in_bom yes)
		(on_board yes)
		(dnp no)
		(property "Reference" "#FLG015"
			(at 128.27 210.185 0)
			(effects
				(font
					(size 1.27 1.27)
				)
				(hide yes)
			)
		)
		(property "Value" "PWR_FLAG"
			(at 127 208.28 0)
			(effects
				(font
					(size 1.27 1.27)
				)
			)
		)
		(property "Footprint" ""
			(at 128.27 212.09 0)
			(effects
				(font
					(size 1.27 1.27)
				)
				(hide yes)
			)
		)
		(property "Datasheet" ""
			(at 128.27 212.09 0)
			(effects
				(font
					(size 1.27 1.27)
				)
				(hide yes)
			)
		)
		(property "Description" ""
			(at 128.27 212.09 0)
			(effects
				(font
					(size 1.27 1.27)
				)
				(hide yes)
			)
		)
		(pin "1"
		)
		(instances
			(project "cm4-baseboard"
				(path ""
					(reference "#FLG015")
					(unit 1)
				)
			)
		)
	)
	(symbol
		(lib_id "antmicroCapacitorsmisc:C_22u_100V_2220")
		(at 231.14 194.31 90)
		(unit 1)
		(exclude_from_sim no)
		(in_bom yes)
		(on_board yes)
		(dnp no)
		(property "Reference" "C406"
			(at 231.775 194.31 90)
			(effects
				(font
					(size 1.27 1.27)
				)
				(justify right)
			)
		)
		(property "Value" "C_22u_100V_2220"
			(at 241.3 173.99 0)
			(effects
				(font
					(size 1.27 1.27)
					(thickness 0.15)
				)
				(justify left bottom)
				(hide yes)
			)
		)
		(property "Footprint" "antmicro-footprints:C_2220_5650Metric"
			(at 243.84 173.99 0)
			(effects
				(font
					(size 1.27 1.27)
					(thickness 0.15)
				)
				(justify left bottom)
				(hide yes)
			)
		)
		(property "Datasheet" "https://product.tdk.com/en/search/capacitor/ceramic/mlcc/info?part_no=C5750X7S2A226M280KB"
			(at 246.38 173.99 0)
			(effects
				(font
					(size 1.27 1.27)
					(thickness 0.15)
				)
				(justify left bottom)
				(hide yes)
			)
		)
		(property "Description" ""
			(at 231.14 194.31 0)
			(effects
				(font
					(size 1.27 1.27)
				)
				(hide yes)
			)
		)
		(property "Manufacturer" "TDK"
			(at 251.46 173.99 0)
			(effects
				(font
					(size 1.27 1.27)
					(thickness 0.15)
				)
				(justify left bottom)
				(hide yes)
			)
		)
		(property "MPN" "C5750X7S2A226M280KB"
			(at 248.92 173.99 0)
			(effects
				(font
					(size 1.27 1.27)
					(thickness 0.15)
				)
				(justify left bottom)
				(hide yes)
			)
		)
		(property "Val" "22u"
			(at 231.775 196.85 90)
			(effects
				(font
					(size 1.27 1.27)
					(thickness 0.15)
				)
				(justify right)
			)
		)
		(property "License" "Apache-2.0"
			(at 254 173.99 0)
			(effects
				(font
					(size 1.27 1.27)
					(thickness 0.15)
				)
				(justify left bottom)
				(hide yes)
			)
		)
		(property "Author" "Antmicro"
			(at 256.54 173.99 0)
			(effects
				(font
					(size 1.27 1.27)
					(thickness 0.15)
				)
				(justify left bottom)
				(hide yes)
			)
		)
		(property "Voltage" "100V"
			(at 231.775 199.39 90)
			(effects
				(font
					(size 1.27 1.27)
				)
				(justify right)
			)
		)
		(property "Dielectric" "X7S"
			(at 261.62 173.99 0)
			(effects
				(font
					(size 1.27 1.27)
				)
				(justify left bottom)
				(hide yes)
			)
		)
		(property "Public" "False"
			(at 264.16 173.99 0)
			(effects
				(font
					(size 1.27 1.27)
				)
				(justify left bottom)
				(hide yes)
			)
		)
		(pin "1"
		)
		(pin "2"
		)
		(instances
			(project "cm4-baseboard"
				(path ""
					(reference "C406")
					(unit 1)
				)
			)
		)
	)
	(symbol
		(lib_id "antmicropower:GNDD")
		(at 278.13 237.49 0)
		(unit 1)
		(exclude_from_sim no)
		(in_bom yes)
		(on_board yes)
		(dnp no)
		(fields_autoplaced yes)
		(property "Reference" "#PWR0413"
			(at 278.13 243.84 0)
			(effects
				(font
					(size 1.27 1.27)
				)
				(justify left bottom)
				(hide yes)
			)
		)
		(property "Value" "GNDD"
			(at 278.13 242.57 0)
			(effects
				(font
					(size 1.27 1.27)
				)
			)
		)
		(property "Footprint" ""
			(at 278.13 237.49 0)
			(effects
				(font
					(size 1.27 1.27)
				)
				(hide yes)
			)
		)
		(property "Datasheet" ""
			(at 278.13 237.49 0)
			(effects
				(font
					(size 1.27 1.27)
				)
				(hide yes)
			)
		)
		(property "Description" ""
			(at 278.13 237.49 0)
			(effects
				(font
					(size 1.27 1.27)
				)
				(hide yes)
			)
		)
		(property "Author" "Antmicro"
			(at 293.37 245.11 0)
			(effects
				(font
					(size 1.27 1.27)
					(thickness 0.15)
				)
				(justify left bottom)
				(hide yes)
			)
		)
		(property "License" "Apache-2.0"
			(at 293.37 247.65 0)
			(effects
				(font
					(size 1.27 1.27)
					(thickness 0.15)
				)
				(justify left bottom)
				(hide yes)
			)
		)
		(pin "1"
		)
		(instances
			(project "cm4-baseboard"
				(path ""
					(reference "#PWR0413")
					(unit 1)
				)
			)
		)
	)
	(symbol
		(lib_id "antmicroResistors0402:R_470k_0402")
		(at 287.02 189.23 90)
		(unit 1)
		(exclude_from_sim no)
		(in_bom no)
		(on_board yes)
		(dnp yes)
		(property "Reference" "R419"
			(at 288.29 185.42 90)
			(effects
				(font
					(size 1.27 1.27)
				)
				(justify right)
			)
		)
		(property "Value" "R_470k_0402"
			(at 299.72 168.91 0)
			(effects
				(font
					(size 1.27 1.27)
					(thickness 0.15)
				)
				(justify left bottom)
				(hide yes)
			)
		)
		(property "Footprint" "antmicro-footprints:R_0402_1005Metric"
			(at 302.26 168.91 0)
			(effects
				(font
					(size 1.27 1.27)
					(thickness 0.15)
				)
				(justify left bottom)
				(hide yes)
			)
		)
		(property "Datasheet" "https://www.bourns.com/docs/product-datasheets/cr.pdf"
			(at 304.8 168.91 0)
			(effects
				(font
					(size 1.27 1.27)
					(thickness 0.15)
				)
				(justify left bottom)
				(hide yes)
			)
		)
		(property "Description" ""
			(at 287.02 189.23 0)
			(effects
				(font
					(size 1.27 1.27)
				)
				(hide yes)
			)
		)
		(property "Manufacturer" "Bourns"
			(at 309.88 168.91 0)
			(effects
				(font
					(size 1.27 1.27)
					(thickness 0.15)
				)
				(justify left bottom)
				(hide yes)
			)
		)
		(property "MPN" "CR0402-FX-4703GLF"
			(at 307.34 168.91 0)
			(effects
				(font
					(size 1.27 1.27)
					(thickness 0.15)
				)
				(justify left bottom)
				(hide yes)
			)
		)
		(property "Val" "470k"
			(at 288.29 187.96 90)
			(effects
				(font
					(size 1.27 1.27)
					(thickness 0.15)
				)
				(justify right)
			)
		)
		(property "License" "Apache-2.0"
			(at 312.42 168.91 0)
			(effects
				(font
					(size 1.27 1.27)
					(thickness 0.15)
				)
				(justify left bottom)
				(hide yes)
			)
		)
		(property "Author" "Antmicro"
			(at 314.96 168.91 0)
			(effects
				(font
					(size 1.27 1.27)
					(thickness 0.15)
				)
				(justify left bottom)
				(hide yes)
			)
		)
		(property "Tolerance" "1%"
			(at 297.18 168.91 0)
			(effects
				(font
					(size 1.27 1.27)
				)
				(justify left bottom)
				(hide yes)
			)
		)
		(pin "1"
		)
		(pin "2"
		)
		(instances
			(project "cm4-baseboard"
				(path ""
					(reference "R419")
					(unit 1)
				)
			)
		)
	)
	(symbol
		(lib_id "antmicroTestPoints:TP_0.75mm_SMD")
		(at 300.99 181.61 90)
		(unit 1)
		(exclude_from_sim no)
		(in_bom no)
		(on_board yes)
		(dnp no)
		(property "Reference" "TP401"
			(at 298.45 175.895 90)
			(effects
				(font
					(size 1.27 1.27)
				)
				(justify right)
			)
		)
		(property "Value" "TP_0.75mm_SMD"
			(at 303.53 181.61 0)
			(effects
				(font
					(size 1.27 1.27)
					(thickness 0.15)
				)
				(justify left bottom)
				(hide yes)
			)
		)
		(property "Footprint" "antmicro-footprints:TP_SMD_0.75mm"
			(at 295.91 176.53 0)
			(effects
				(font
					(size 1.27 1.27)
					(thickness 0.15)
				)
				(justify left bottom)
				(hide yes)
			)
		)
		(property "Datasheet" ""
			(at 293.37 176.53 0)
			(effects
				(font
					(size 1.27 1.27)
					(thickness 0.15)
				)
				(justify left bottom)
				(hide yes)
			)
		)
		(property "Description" ""
			(at 300.99 181.61 0)
			(effects
				(font
					(size 1.27 1.27)
				)
				(hide yes)
			)
		)
		(property "MPN" ""
			(at 300.99 181.61 0)
			(effects
				(font
					(size 1.27 1.27)
					(thickness 0.15)
				)
				(justify left bottom)
				(hide yes)
			)
		)
		(property "Manufacturer" ""
			(at 300.99 181.61 0)
			(effects
				(font
					(size 1.27 1.27)
					(thickness 0.15)
				)
				(justify left bottom)
				(hide yes)
			)
		)
		(property "Author" "Antmicro"
			(at 316.23 166.37 0)
			(effects
				(font
					(size 1.27 1.27)
					(thickness 0.15)
				)
				(justify left bottom)
				(hide yes)
			)
		)
		(property "License" "Apache-2.0"
			(at 318.77 166.37 0)
			(effects
				(font
					(size 1.27 1.27)
					(thickness 0.15)
				)
				(justify left bottom)
				(hide yes)
			)
		)
		(pin "1"
		)
		(instances
			(project "cm4-baseboard"
				(path ""
					(reference "TP401")
					(unit 1)
				)
			)
		)
	)
	(symbol
		(lib_id "antmicroTransistorsFETsMOSFETsSingle:PJE138K")
		(at 269.24 207.01 0)
		(unit 1)
		(exclude_from_sim no)
		(in_bom yes)
		(on_board yes)
		(dnp no)
		(property "Reference" "Q401"
			(at 279.4 203.2 0)
			(effects
				(font
					(size 1.27 1.27)
				)
				(justify left)
			)
		)
		(property "Value" "PJE138K"
			(at 279.4 205.74 0)
			(effects
				(font
					(size 1.27 1.27)
					(thickness 0.15)
				)
				(justify left)
			)
		)
		(property "Footprint" "antmicro-footprints:SOT-523"
			(at 292.1 218.44 0)
			(effects
				(font
					(size 1.27 1.27)
					(thickness 0.15)
				)
				(justify left bottom)
				(hide yes)
			)
		)
		(property "Datasheet" "https://www.mouser.com/datasheet/2/1057/PJE138K-1876698.pdf"
			(at 292.1 220.98 0)
			(effects
				(font
					(size 1.27 1.27)
					(thickness 0.15)
				)
				(justify left bottom)
				(hide yes)
			)
		)
		(property "Description" ""
			(at 269.24 207.01 0)
			(effects
				(font
					(size 1.27 1.27)
				)
				(hide yes)
			)
		)
		(property "MPN" "PJE138K_R1_00001"
			(at 292.1 223.52 0)
			(effects
				(font
					(size 1.27 1.27)
					(thickness 0.15)
				)
				(justify left bottom)
				(hide yes)
			)
		)
		(property "Manufacturer" "PANJIT"
			(at 292.1 226.06 0)
			(effects
				(font
					(size 1.27 1.27)
					(thickness 0.15)
				)
				(justify left bottom)
				(hide yes)
			)
		)
		(property "Author" "Antmicro"
			(at 292.1 228.6 0)
			(effects
				(font
					(size 1.27 1.27)
					(thickness 0.15)
				)
				(justify left bottom)
				(hide yes)
			)
		)
		(property "License" "Apache-2.0"
			(at 292.1 231.14 0)
			(effects
				(font
					(size 1.27 1.27)
					(thickness 0.15)
				)
				(justify left bottom)
				(hide yes)
			)
		)
		(pin "1"
		)
		(pin "2"
		)
		(pin "3"
		)
		(instances
			(project "cm4-baseboard"
				(path ""
					(reference "Q401")
					(unit 1)
				)
			)
		)
	)
	(symbol
		(lib_id "antmicroResistors0402:R_100k_0402")
		(at 287.02 203.2 90)
		(unit 1)
		(exclude_from_sim no)
		(in_bom no)
		(on_board yes)
		(dnp yes)
		(property "Reference" "R420"
			(at 288.29 199.39 90)
			(effects
				(font
					(size 1.27 1.27)
				)
				(justify right)
			)
		)
		(property "Value" "R_100k_0402"
			(at 299.72 182.88 0)
			(effects
				(font
					(size 1.27 1.27)
					(thickness 0.15)
				)
				(justify left bottom)
				(hide yes)
			)
		)
		(property "Footprint" "antmicro-footprints:R_0402_1005Metric"
			(at 302.26 182.88 0)
			(effects
				(font
					(size 1.27 1.27)
					(thickness 0.15)
				)
				(justify left bottom)
				(hide yes)
			)
		)
		(property "Datasheet" "https://www.bourns.com/docs/product-datasheets/cr.pdf"
			(at 304.8 182.88 0)
			(effects
				(font
					(size 1.27 1.27)
					(thickness 0.15)
				)
				(justify left bottom)
				(hide yes)
			)
		)
		(property "Description" ""
			(at 287.02 203.2 0)
			(effects
				(font
					(size 1.27 1.27)
				)
				(hide yes)
			)
		)
		(property "Manufacturer" "Bourns"
			(at 309.88 182.88 0)
			(effects
				(font
					(size 1.27 1.27)
					(thickness 0.15)
				)
				(justify left bottom)
				(hide yes)
			)
		)
		(property "MPN" "CR0402-FX-1003GLF"
			(at 307.34 182.88 0)
			(effects
				(font
					(size 1.27 1.27)
					(thickness 0.15)
				)
				(justify left bottom)
				(hide yes)
			)
		)
		(property "Val" "100k"
			(at 288.29 201.93 90)
			(effects
				(font
					(size 1.27 1.27)
					(thickness 0.15)
				)
				(justify right)
			)
		)
		(property "License" "Apache-2.0"
			(at 312.42 182.88 0)
			(effects
				(font
					(size 1.27 1.27)
					(thickness 0.15)
				)
				(justify left bottom)
				(hide yes)
			)
		)
		(property "Author" "Antmicro"
			(at 314.96 182.88 0)
			(effects
				(font
					(size 1.27 1.27)
					(thickness 0.15)
				)
				(justify left bottom)
				(hide yes)
			)
		)
		(property "Tolerance" "1%"
			(at 297.18 182.88 0)
			(effects
				(font
					(size 1.27 1.27)
				)
				(justify left bottom)
				(hide yes)
			)
		)
		(pin "1"
		)
		(pin "2"
		)
		(instances
			(project "cm4-baseboard"
				(path ""
					(reference "R420")
					(unit 1)
				)
			)
		)
	)
	(symbol
		(lib_id "antmicropower:GNDD")
		(at 224.79 201.93 0)
		(unit 1)
		(exclude_from_sim no)
		(in_bom yes)
		(on_board yes)
		(dnp no)
		(fields_autoplaced yes)
		(property "Reference" "#PWR0407"
			(at 224.79 208.28 0)
			(effects
				(font
					(size 1.27 1.27)
				)
				(justify left bottom)
				(hide yes)
			)
		)
		(property "Value" "GNDD"
			(at 224.79 206.375 0)
			(effects
				(font
					(size 1.27 1.27)
				)
			)
		)
		(property "Footprint" ""
			(at 224.79 201.93 0)
			(effects
				(font
					(size 1.27 1.27)
				)
				(hide yes)
			)
		)
		(property "Datasheet" ""
			(at 224.79 201.93 0)
			(effects
				(font
					(size 1.27 1.27)
				)
				(hide yes)
			)
		)
		(property "Description" ""
			(at 224.79 201.93 0)
			(effects
				(font
					(size 1.27 1.27)
				)
				(hide yes)
			)
		)
		(property "Author" "Antmicro"
			(at 240.03 209.55 0)
			(effects
				(font
					(size 1.27 1.27)
					(thickness 0.15)
				)
				(justify left bottom)
				(hide yes)
			)
		)
		(property "License" "Apache-2.0"
			(at 240.03 212.09 0)
			(effects
				(font
					(size 1.27 1.27)
					(thickness 0.15)
				)
				(justify left bottom)
				(hide yes)
			)
		)
		(pin "1"
		)
		(instances
			(project "cm4-baseboard"
				(path ""
					(reference "#PWR0407")
					(unit 1)
				)
			)
		)
	)
	(symbol
		(lib_id "antmicroResistors0402:R_470R_0402")
		(at 299.72 236.22 0)
		(unit 1)
		(exclude_from_sim no)
		(in_bom yes)
		(on_board yes)
		(dnp no)
		(property "Reference" "R421"
			(at 302.26 234.315 0)
			(effects
				(font
					(size 1.27 1.27)
				)
			)
		)
		(property "Value" "R_470R_0402"
			(at 320.04 248.92 0)
			(effects
				(font
					(size 1.27 1.27)
					(thickness 0.15)
				)
				(justify left bottom)
				(hide yes)
			)
		)
		(property "Footprint" "antmicro-footprints:R_0402_1005Metric"
			(at 320.04 251.46 0)
			(effects
				(font
					(size 1.27 1.27)
					(thickness 0.15)
				)
				(justify left bottom)
				(hide yes)
			)
		)
		(property "Datasheet" "https://www.bourns.com/docs/product-datasheets/cr.pdf"
			(at 320.04 254 0)
			(effects
				(font
					(size 1.27 1.27)
					(thickness 0.15)
				)
				(justify left bottom)
				(hide yes)
			)
		)
		(property "Description" ""
			(at 299.72 236.22 0)
			(effects
				(font
					(size 1.27 1.27)
				)
				(hide yes)
			)
		)
		(property "Manufacturer" "Bourns"
			(at 320.04 259.08 0)
			(effects
				(font
					(size 1.27 1.27)
					(thickness 0.15)
				)
				(justify left bottom)
				(hide yes)
			)
		)
		(property "MPN" "CR0402-FX-4700GLF"
			(at 320.04 256.54 0)
			(effects
				(font
					(size 1.27 1.27)
					(thickness 0.15)
				)
				(justify left bottom)
				(hide yes)
			)
		)
		(property "Val" "470R"
			(at 302.26 238.125 0)
			(effects
				(font
					(size 1.27 1.27)
					(thickness 0.15)
				)
			)
		)
		(property "License" "Apache-2.0"
			(at 320.04 261.62 0)
			(effects
				(font
					(size 1.27 1.27)
					(thickness 0.15)
				)
				(justify left bottom)
				(hide yes)
			)
		)
		(property "Author" "Antmicro"
			(at 320.04 264.16 0)
			(effects
				(font
					(size 1.27 1.27)
					(thickness 0.15)
				)
				(justify left bottom)
				(hide yes)
			)
		)
		(property "Tolerance" "1%"
			(at 320.04 246.38 0)
			(effects
				(font
					(size 1.27 1.27)
				)
				(justify left bottom)
				(hide yes)
			)
		)
		(pin "1"
		)
		(pin "2"
		)
		(instances
			(project "cm4-baseboard"
				(path ""
					(reference "R421")
					(unit 1)
				)
			)
		)
	)
	(symbol
		(lib_id "antmicropower:GND")
		(at 367.03 199.39 0)
		(unit 1)
		(exclude_from_sim no)
		(in_bom yes)
		(on_board yes)
		(dnp no)
		(fields_autoplaced yes)
		(property "Reference" "#PWR0417"
			(at 367.03 205.74 0)
			(effects
				(font
					(size 1.27 1.27)
				)
				(justify left bottom)
				(hide yes)
			)
		)
		(property "Value" "GND"
			(at 367.03 204.47 0)
			(effects
				(font
					(size 1.27 1.27)
				)
			)
		)
		(property "Footprint" ""
			(at 375.92 207.01 0)
			(effects
				(font
					(size 1.27 1.27)
					(thickness 0.15)
				)
				(justify left bottom)
				(hide yes)
			)
		)
		(property "Datasheet" ""
			(at 375.92 212.09 0)
			(effects
				(font
					(size 1.27 1.27)
					(thickness 0.15)
				)
				(justify left bottom)
				(hide yes)
			)
		)
		(property "Description" ""
			(at 367.03 199.39 0)
			(effects
				(font
					(size 1.27 1.27)
				)
				(hide yes)
			)
		)
		(property "Author" "Antmicro"
			(at 375.92 207.01 0)
			(effects
				(font
					(size 1.27 1.27)
					(thickness 0.15)
				)
				(justify left bottom)
				(hide yes)
			)
		)
		(property "License" "Apache-2.0"
			(at 375.92 209.55 0)
			(effects
				(font
					(size 1.27 1.27)
					(thickness 0.15)
				)
				(justify left bottom)
				(hide yes)
			)
		)
		(pin "1"
		)
		(instances
			(project "cm4-baseboard"
				(path ""
					(reference "#PWR0417")
					(unit 1)
				)
			)
		)
	)
	(symbol
		(lib_id "antmicropower:GND")
		(at 218.44 95.25 0)
		(mirror y)
		(unit 1)
		(exclude_from_sim no)
		(in_bom yes)
		(on_board yes)
		(dnp no)
		(fields_autoplaced yes)
		(property "Reference" "#PWR0406"
			(at 218.44 101.6 0)
			(effects
				(font
					(size 1.27 1.27)
				)
				(justify left bottom)
				(hide yes)
			)
		)
		(property "Value" "GND"
			(at 218.44 100.33 0)
			(effects
				(font
					(size 1.27 1.27)
				)
			)
		)
		(property "Footprint" ""
			(at 209.55 102.87 0)
			(effects
				(font
					(size 1.27 1.27)
					(thickness 0.15)
				)
				(justify left bottom)
				(hide yes)
			)
		)
		(property "Datasheet" ""
			(at 209.55 107.95 0)
			(effects
				(font
					(size 1.27 1.27)
					(thickness 0.15)
				)
				(justify left bottom)
				(hide yes)
			)
		)
		(property "Description" ""
			(at 218.44 95.25 0)
			(effects
				(font
					(size 1.27 1.27)
				)
				(hide yes)
			)
		)
		(property "Author" "Antmicro"
			(at 209.55 102.87 0)
			(effects
				(font
					(size 1.27 1.27)
					(thickness 0.15)
				)
				(justify left bottom)
				(hide yes)
			)
		)
		(property "License" "Apache-2.0"
			(at 209.55 105.41 0)
			(effects
				(font
					(size 1.27 1.27)
					(thickness 0.15)
				)
				(justify left bottom)
				(hide yes)
			)
		)
		(pin "1"
		)
		(instances
			(project "cm4-baseboard"
				(path ""
					(reference "#PWR0406")
					(unit 1)
				)
			)
		)
	)
	(symbol
		(lib_id "antmicroCapacitorsmisc:C_22u_25V_0805")
		(at 358.14 187.96 90)
		(mirror x)
		(unit 1)
		(exclude_from_sim no)
		(in_bom yes)
		(on_board yes)
		(dnp no)
		(property "Reference" "C410"
			(at 359.41 191.77 90)
			(effects
				(font
					(size 1.27 1.27)
				)
				(justify right)
			)
		)
		(property "Value" "C_22u_25V_0805"
			(at 361.95 187.96 0)
			(effects
				(font
					(size 1.27 1.27)
				)
				(justify left bottom)
				(hide yes)
			)
		)
		(property "Footprint" "antmicro-footprints:C_0805_2012Metric"
			(at 353.06 193.04 0)
			(effects
				(font
					(size 1.524 1.524)
				)
				(justify left bottom)
				(hide yes)
			)
		)
		(property "Datasheet" "https://product.samsungsem.com/mlcc/CL21A226MAYNNN.do"
			(at 358.14 187.96 0)
			(effects
				(font
					(size 1.27 1.27)
				)
				(justify left bottom)
				(hide yes)
			)
		)
		(property "Description" ""
			(at 358.14 187.96 0)
			(effects
				(font
					(size 1.27 1.27)
				)
				(hide yes)
			)
		)
		(property "Manufacturer" "Samsung Electro-Mechanics"
			(at 347.98 193.04 0)
			(effects
				(font
					(size 1.524 1.524)
				)
				(justify left bottom)
				(hide yes)
			)
		)
		(property "MPN" "CL21A226MAYNNNE"
			(at 350.52 193.04 0)
			(effects
				(font
					(size 1.524 1.524)
				)
				(justify left bottom)
				(hide yes)
			)
		)
		(property "Val" "22u"
			(at 359.41 194.31 90)
			(effects
				(font
					(size 1.27 1.27)
				)
				(justify right)
			)
		)
		(property "License" "Apache-2.0"
			(at 381 208.28 0)
			(effects
				(font
					(size 1.27 1.27)
					(thickness 0.15)
				)
				(justify left bottom)
				(hide yes)
			)
		)
		(property "Author" "Antmicro"
			(at 383.54 208.28 0)
			(effects
				(font
					(size 1.27 1.27)
					(thickness 0.15)
				)
				(justify left bottom)
				(hide yes)
			)
		)
		(property "Voltage" "25V"
			(at 359.41 196.85 90)
			(effects
				(font
					(size 1.27 1.27)
				)
				(justify right)
			)
		)
		(property "Dielectric" "X5R"
			(at 388.62 208.28 0)
			(effects
				(font
					(size 1.27 1.27)
				)
				(justify left bottom)
				(hide yes)
			)
		)
		(property "Public" "False"
			(at 391.16 208.28 0)
			(effects
				(font
					(size 1.27 1.27)
				)
				(justify left bottom)
				(hide yes)
			)
		)
		(pin "1"
		)
		(pin "2"
		)
		(instances
			(project "cm4-baseboard"
				(path ""
					(reference "C410")
					(unit 1)
				)
			)
		)
	)
	(symbol
		(lib_id "antmicroResistors0402:R_470k_0402")
		(at 266.7 189.23 90)
		(unit 1)
		(exclude_from_sim no)
		(in_bom yes)
		(on_board yes)
		(dnp no)
		(property "Reference" "R415"
			(at 265.43 185.42 90)
			(effects
				(font
					(size 1.27 1.27)
				)
				(justify left)
			)
		)
		(property "Value" "R_470k_0402"
			(at 279.4 168.91 0)
			(effects
				(font
					(size 1.27 1.27)
					(thickness 0.15)
				)
				(justify left bottom)
				(hide yes)
			)
		)
		(property "Footprint" "antmicro-footprints:R_0402_1005Metric"
			(at 281.94 168.91 0)
			(effects
				(font
					(size 1.27 1.27)
					(thickness 0.15)
				)
				(justify left bottom)
				(hide yes)
			)
		)
		(property "Datasheet" "https://www.bourns.com/docs/product-datasheets/cr.pdf"
			(at 284.48 168.91 0)
			(effects
				(font
					(size 1.27 1.27)
					(thickness 0.15)
				)
				(justify left bottom)
				(hide yes)
			)
		)
		(property "Description" ""
			(at 266.7 189.23 0)
			(effects
				(font
					(size 1.27 1.27)
				)
				(hide yes)
			)
		)
		(property "Manufacturer" "Bourns"
			(at 289.56 168.91 0)
			(effects
				(font
					(size 1.27 1.27)
					(thickness 0.15)
				)
				(justify left bottom)
				(hide yes)
			)
		)
		(property "MPN" "CR0402-FX-4703GLF"
			(at 287.02 168.91 0)
			(effects
				(font
					(size 1.27 1.27)
					(thickness 0.15)
				)
				(justify left bottom)
				(hide yes)
			)
		)
		(property "Val" "470k"
			(at 265.43 187.96 90)
			(effects
				(font
					(size 1.27 1.27)
					(thickness 0.15)
				)
				(justify left)
			)
		)
		(property "License" "Apache-2.0"
			(at 292.1 168.91 0)
			(effects
				(font
					(size 1.27 1.27)
					(thickness 0.15)
				)
				(justify left bottom)
				(hide yes)
			)
		)
		(property "Author" "Antmicro"
			(at 294.64 168.91 0)
			(effects
				(font
					(size 1.27 1.27)
					(thickness 0.15)
				)
				(justify left bottom)
				(hide yes)
			)
		)
		(property "Tolerance" "1%"
			(at 276.86 168.91 0)
			(effects
				(font
					(size 1.27 1.27)
				)
				(justify left bottom)
				(hide yes)
			)
		)
		(pin "1"
		)
		(pin "2"
		)
		(instances
			(project "cm4-baseboard"
				(path ""
					(reference "R415")
					(unit 1)
				)
			)
		)
	)
	(symbol
		(lib_id "antmicroResistors0402:R_200R_0402")
		(at 213.36 76.2 0)
		(mirror x)
		(unit 1)
		(exclude_from_sim no)
		(in_bom yes)
		(on_board yes)
		(dnp no)
		(property "Reference" "R411"
			(at 210.82 74.93 0)
			(effects
				(font
					(size 1.27 1.27)
				)
			)
		)
		(property "Value" "R_200R_0402"
			(at 233.68 63.5 0)
			(effects
				(font
					(size 1.27 1.27)
					(thickness 0.15)
				)
				(justify left bottom)
				(hide yes)
			)
		)
		(property "Footprint" "antmicro-footprints:R_0402_1005Metric"
			(at 233.68 60.96 0)
			(effects
				(font
					(size 1.27 1.27)
					(thickness 0.15)
				)
				(justify left bottom)
				(hide yes)
			)
		)
		(property "Datasheet" "https://www.bourns.com/docs/product-datasheets/cr.pdf"
			(at 233.68 58.42 0)
			(effects
				(font
					(size 1.27 1.27)
					(thickness 0.15)
				)
				(justify left bottom)
				(hide yes)
			)
		)
		(property "Description" ""
			(at 213.36 76.2 0)
			(effects
				(font
					(size 1.27 1.27)
				)
				(hide yes)
			)
		)
		(property "Manufacturer" "Bourns"
			(at 233.68 53.34 0)
			(effects
				(font
					(size 1.27 1.27)
					(thickness 0.15)
				)
				(justify left bottom)
				(hide yes)
			)
		)
		(property "MPN" "CR0402-FX-2000GLF"
			(at 233.68 55.88 0)
			(effects
				(font
					(size 1.27 1.27)
					(thickness 0.15)
				)
				(justify left bottom)
				(hide yes)
			)
		)
		(property "Val" "200R"
			(at 220.98 74.93 0)
			(effects
				(font
					(size 1.27 1.27)
					(thickness 0.15)
				)
			)
		)
		(property "License" "Apache-2.0"
			(at 233.68 50.8 0)
			(effects
				(font
					(size 1.27 1.27)
					(thickness 0.15)
				)
				(justify left bottom)
				(hide yes)
			)
		)
		(property "Author" "Antmicro"
			(at 233.68 48.26 0)
			(effects
				(font
					(size 1.27 1.27)
					(thickness 0.15)
				)
				(justify left bottom)
				(hide yes)
			)
		)
		(property "Tolerance" "1%"
			(at 233.68 66.04 0)
			(effects
				(font
					(size 1.27 1.27)
				)
				(justify left bottom)
				(hide yes)
			)
		)
		(pin "1"
		)
		(pin "2"
		)
		(instances
			(project "cm4-baseboard"
				(path ""
					(reference "R411")
					(unit 1)
				)
			)
		)
	)
	(symbol
		(lib_id "antmicropower:GNDD")
		(at 304.8 200.66 0)
		(unit 1)
		(exclude_from_sim no)
		(in_bom yes)
		(on_board yes)
		(dnp no)
		(fields_autoplaced yes)
		(property "Reference" "#PWR0415"
			(at 304.8 207.01 0)
			(effects
				(font
					(size 1.27 1.27)
				)
				(justify left bottom)
				(hide yes)
			)
		)
		(property "Value" "GNDD"
			(at 304.8 205.74 0)
			(effects
				(font
					(size 1.27 1.27)
				)
			)
		)
		(property "Footprint" ""
			(at 304.8 200.66 0)
			(effects
				(font
					(size 1.27 1.27)
				)
				(hide yes)
			)
		)
		(property "Datasheet" ""
			(at 304.8 200.66 0)
			(effects
				(font
					(size 1.27 1.27)
				)
				(hide yes)
			)
		)
		(property "Description" ""
			(at 304.8 200.66 0)
			(effects
				(font
					(size 1.27 1.27)
				)
				(hide yes)
			)
		)
		(property "Author" "Antmicro"
			(at 320.04 208.28 0)
			(effects
				(font
					(size 1.27 1.27)
					(thickness 0.15)
				)
				(justify left bottom)
				(hide yes)
			)
		)
		(property "License" "Apache-2.0"
			(at 320.04 210.82 0)
			(effects
				(font
					(size 1.27 1.27)
					(thickness 0.15)
				)
				(justify left bottom)
				(hide yes)
			)
		)
		(pin "1"
		)
		(instances
			(project "cm4-baseboard"
				(path ""
					(reference "#PWR0415")
					(unit 1)
				)
			)
		)
	)
	(symbol
		(lib_id "antmicroTestPoints:TP_0.75mm_SMD")
		(at 299.72 214.63 270)
		(mirror x)
		(unit 1)
		(exclude_from_sim no)
		(in_bom no)
		(on_board yes)
		(dnp no)
		(fields_autoplaced yes)
		(property "Reference" "TP402"
			(at 297.815 211.4549 90)
			(effects
				(font
					(size 1.27 1.27)
				)
				(justify right)
			)
		)
		(property "Value" "TP_0.75mm_SMD"
			(at 297.18 214.63 0)
			(effects
				(font
					(size 1.27 1.27)
					(thickness 0.15)
				)
				(justify left bottom)
				(hide yes)
			)
		)
		(property "Footprint" "antmicro-footprints:TP_SMD_0.75mm"
			(at 304.8 209.55 0)
			(effects
				(font
					(size 1.27 1.27)
					(thickness 0.15)
				)
				(justify left bottom)
				(hide yes)
			)
		)
		(property "Datasheet" ""
			(at 307.34 209.55 0)
			(effects
				(font
					(size 1.27 1.27)
					(thickness 0.15)
				)
				(justify left bottom)
				(hide yes)
			)
		)
		(property "Description" ""
			(at 299.72 214.63 0)
			(effects
				(font
					(size 1.27 1.27)
				)
				(hide yes)
			)
		)
		(property "MPN" ""
			(at 299.72 214.63 0)
			(effects
				(font
					(size 1.27 1.27)
					(thickness 0.15)
				)
				(justify left bottom)
				(hide yes)
			)
		)
		(property "Manufacturer" ""
			(at 299.72 214.63 0)
			(effects
				(font
					(size 1.27 1.27)
					(thickness 0.15)
				)
				(justify left bottom)
				(hide yes)
			)
		)
		(property "Author" "Antmicro"
			(at 284.48 199.39 0)
			(effects
				(font
					(size 1.27 1.27)
					(thickness 0.15)
				)
				(justify left bottom)
				(hide yes)
			)
		)
		(property "License" "Apache-2.0"
			(at 281.94 199.39 0)
			(effects
				(font
					(size 1.27 1.27)
					(thickness 0.15)
				)
				(justify left bottom)
				(hide yes)
			)
		)
		(pin "1"
		)
		(instances
			(project "cm4-baseboard"
				(path ""
					(reference "TP402")
					(unit 1)
				)
			)
		)
	)
	(symbol
		(lib_id "antmicroResistors0402:R_200R_0402")
		(at 213.36 81.28 0)
		(mirror x)
		(unit 1)
		(exclude_from_sim no)
		(in_bom yes)
		(on_board yes)
		(dnp no)
		(property "Reference" "R412"
			(at 210.82 80.01 0)
			(effects
				(font
					(size 1.27 1.27)
				)
			)
		)
		(property "Value" "R_200R_0402"
			(at 233.68 68.58 0)
			(effects
				(font
					(size 1.27 1.27)
					(thickness 0.15)
				)
				(justify left bottom)
				(hide yes)
			)
		)
		(property "Footprint" "antmicro-footprints:R_0402_1005Metric"
			(at 233.68 66.04 0)
			(effects
				(font
					(size 1.27 1.27)
					(thickness 0.15)
				)
				(justify left bottom)
				(hide yes)
			)
		)
		(property "Datasheet" "https://www.bourns.com/docs/product-datasheets/cr.pdf"
			(at 233.68 63.5 0)
			(effects
				(font
					(size 1.27 1.27)
					(thickness 0.15)
				)
				(justify left bottom)
				(hide yes)
			)
		)
		(property "Description" ""
			(at 213.36 81.28 0)
			(effects
				(font
					(size 1.27 1.27)
				)
				(hide yes)
			)
		)
		(property "Manufacturer" "Bourns"
			(at 233.68 58.42 0)
			(effects
				(font
					(size 1.27 1.27)
					(thickness 0.15)
				)
				(justify left bottom)
				(hide yes)
			)
		)
		(property "MPN" "CR0402-FX-2000GLF"
			(at 233.68 60.96 0)
			(effects
				(font
					(size 1.27 1.27)
					(thickness 0.15)
				)
				(justify left bottom)
				(hide yes)
			)
		)
		(property "Val" "200R"
			(at 220.98 80.01 0)
			(effects
				(font
					(size 1.27 1.27)
					(thickness 0.15)
				)
			)
		)
		(property "License" "Apache-2.0"
			(at 233.68 55.88 0)
			(effects
				(font
					(size 1.27 1.27)
					(thickness 0.15)
				)
				(justify left bottom)
				(hide yes)
			)
		)
		(property "Author" "Antmicro"
			(at 233.68 53.34 0)
			(effects
				(font
					(size 1.27 1.27)
					(thickness 0.15)
				)
				(justify left bottom)
				(hide yes)
			)
		)
		(property "Tolerance" "1%"
			(at 233.68 71.12 0)
			(effects
				(font
					(size 1.27 1.27)
				)
				(justify left bottom)
				(hide yes)
			)
		)
		(pin "1"
		)
		(pin "2"
		)
		(instances
			(project "cm4-baseboard"
				(path ""
					(reference "R412")
					(unit 1)
				)
			)
		)
	)
	(symbol
		(lib_id "antmicroDiodesRectifiersSingle:CD-MMBL110S")
		(at 69.85 177.8 0)
		(unit 1)
		(exclude_from_sim no)
		(in_bom yes)
		(on_board yes)
		(dnp no)
		(property "Reference" "D401"
			(at 78.74 172.72 0)
			(effects
				(font
					(size 1.27 1.27)
				)
			)
		)
		(property "Value" "CD-MMBL110S"
			(at 78.74 175.26 0)
			(effects
				(font
					(size 1.27 1.27)
					(thickness 0.15)
				)
			)
		)
		(property "Footprint" "antmicro-footprints:DFN3538"
			(at 101.6 187.96 0)
			(effects
				(font
					(size 1.27 1.27)
					(thickness 0.15)
				)
				(justify left bottom)
				(hide yes)
			)
		)
		(property "Datasheet" "https://www.bourns.com/docs/product-datasheets/CD-MMBL110S.pdf"
			(at 101.6 190.5 0)
			(effects
				(font
					(size 1.27 1.27)
					(thickness 0.15)
				)
				(justify left bottom)
				(hide yes)
			)
		)
		(property "Description" ""
			(at 69.85 177.8 0)
			(effects
				(font
					(size 1.27 1.27)
				)
				(hide yes)
			)
		)
		(property "MPN" "CD-MMBL110S"
			(at 101.6 193.04 0)
			(effects
				(font
					(size 1.27 1.27)
					(thickness 0.15)
				)
				(justify left bottom)
				(hide yes)
			)
		)
		(property "Manufacturer" "Bourns"
			(at 101.6 195.58 0)
			(effects
				(font
					(size 1.27 1.27)
					(thickness 0.15)
				)
				(justify left bottom)
				(hide yes)
			)
		)
		(property "Author" "Antmicro"
			(at 101.6 198.12 0)
			(effects
				(font
					(size 1.27 1.27)
					(thickness 0.15)
				)
				(justify left bottom)
				(hide yes)
			)
		)
		(property "License" "Apache-2.0"
			(at 101.6 200.66 0)
			(effects
				(font
					(size 1.27 1.27)
					(thickness 0.15)
				)
				(justify left bottom)
				(hide yes)
			)
		)
		(pin "1"
		)
		(pin "2"
		)
		(pin "3"
		)
		(pin "4"
		)
		(instances
			(project "cm4-baseboard"
				(path ""
					(reference "D401")
					(unit 1)
				)
			)
		)
	)
	(symbol
		(lib_id "antmicroResistors0402:R_0R_0402")
		(at 331.47 184.15 270)
		(unit 1)
		(exclude_from_sim no)
		(in_bom no)
		(on_board yes)
		(dnp yes)
		(property "Reference" "R422"
			(at 332.74 185.42 90)
			(effects
				(font
					(size 1.27 1.27)
				)
				(justify left)
			)
		)
		(property "Value" "R_0R_0402"
			(at 318.77 204.47 0)
			(effects
				(font
					(size 1.27 1.27)
					(thickness 0.15)
				)
				(justify left bottom)
				(hide yes)
			)
		)
		(property "Footprint" "antmicro-footprints:R_0402_1005Metric"
			(at 316.23 204.47 0)
			(effects
				(font
					(size 1.27 1.27)
					(thickness 0.15)
				)
				(justify left bottom)
				(hide yes)
			)
		)
		(property "Datasheet" "https://industrial.panasonic.com/cdbs/www-data/pdf/RDA0000/AOA0000C301.pdf"
			(at 313.69 204.47 0)
			(effects
				(font
					(size 1.27 1.27)
					(thickness 0.15)
				)
				(justify left bottom)
				(hide yes)
			)
		)
		(property "Description" ""
			(at 331.47 184.15 0)
			(effects
				(font
					(size 1.27 1.27)
				)
				(hide yes)
			)
		)
		(property "Manufacturer" "Panasonic"
			(at 308.61 204.47 0)
			(effects
				(font
					(size 1.27 1.27)
					(thickness 0.15)
				)
				(justify left bottom)
				(hide yes)
			)
		)
		(property "MPN" "ERJ2GE0R00X"
			(at 311.15 204.47 0)
			(effects
				(font
					(size 1.27 1.27)
					(thickness 0.15)
				)
				(justify left bottom)
				(hide yes)
			)
		)
		(property "Val" "0R"
			(at 332.74 187.96 90)
			(effects
				(font
					(size 1.27 1.27)
					(thickness 0.15)
				)
				(justify left)
			)
		)
		(property "License" "Apache-2.0"
			(at 306.07 204.47 0)
			(effects
				(font
					(size 1.27 1.27)
					(thickness 0.15)
				)
				(justify left bottom)
				(hide yes)
			)
		)
		(property "Author" "Antmicro"
			(at 303.53 204.47 0)
			(effects
				(font
					(size 1.27 1.27)
					(thickness 0.15)
				)
				(justify left bottom)
				(hide yes)
			)
		)
		(property "Tolerance" "~"
			(at 321.31 204.47 0)
			(effects
				(font
					(size 1.27 1.27)
				)
				(justify left bottom)
				(hide yes)
			)
		)
		(property "Current" "1A"
			(at 330.2 183.515 0)
			(effects
				(font
					(size 1.27 1.27)
					(thickness 0.15)
				)
				(hide yes)
			)
		)
		(pin "1"
		)
		(pin "2"
		)
		(instances
			(project "cm4-baseboard"
				(path ""
					(reference "R422")
					(unit 1)
				)
			)
		)
	)
	(symbol
		(lib_id "antmicroCapacitorsmisc:C_22u_100V_2220")
		(at 217.17 194.31 90)
		(unit 1)
		(exclude_from_sim no)
		(in_bom yes)
		(on_board yes)
		(dnp no)
		(property "Reference" "C404"
			(at 217.805 194.31 90)
			(effects
				(font
					(size 1.27 1.27)
				)
				(justify right)
			)
		)
		(property "Value" "C_22u_100V_2220"
			(at 227.33 173.99 0)
			(effects
				(font
					(size 1.27 1.27)
					(thickness 0.15)
				)
				(justify left bottom)
				(hide yes)
			)
		)
		(property "Footprint" "antmicro-footprints:C_2220_5650Metric"
			(at 229.87 173.99 0)
			(effects
				(font
					(size 1.27 1.27)
					(thickness 0.15)
				)
				(justify left bottom)
				(hide yes)
			)
		)
		(property "Datasheet" "https://product.tdk.com/en/search/capacitor/ceramic/mlcc/info?part_no=C5750X7S2A226M280KB"
			(at 232.41 173.99 0)
			(effects
				(font
					(size 1.27 1.27)
					(thickness 0.15)
				)
				(justify left bottom)
				(hide yes)
			)
		)
		(property "Description" ""
			(at 217.17 194.31 0)
			(effects
				(font
					(size 1.27 1.27)
				)
				(hide yes)
			)
		)
		(property "Manufacturer" "TDK"
			(at 237.49 173.99 0)
			(effects
				(font
					(size 1.27 1.27)
					(thickness 0.15)
				)
				(justify left bottom)
				(hide yes)
			)
		)
		(property "MPN" "C5750X7S2A226M280KB"
			(at 234.95 173.99 0)
			(effects
				(font
					(size 1.27 1.27)
					(thickness 0.15)
				)
				(justify left bottom)
				(hide yes)
			)
		)
		(property "Val" "22u"
			(at 217.805 196.85 90)
			(effects
				(font
					(size 1.27 1.27)
					(thickness 0.15)
				)
				(justify right)
			)
		)
		(property "License" "Apache-2.0"
			(at 240.03 173.99 0)
			(effects
				(font
					(size 1.27 1.27)
					(thickness 0.15)
				)
				(justify left bottom)
				(hide yes)
			)
		)
		(property "Author" "Antmicro"
			(at 242.57 173.99 0)
			(effects
				(font
					(size 1.27 1.27)
					(thickness 0.15)
				)
				(justify left bottom)
				(hide yes)
			)
		)
		(property "Voltage" "100V"
			(at 217.805 199.39 90)
			(effects
				(font
					(size 1.27 1.27)
				)
				(justify right)
			)
		)
		(property "Dielectric" "X7S"
			(at 247.65 173.99 0)
			(effects
				(font
					(size 1.27 1.27)
				)
				(justify left bottom)
				(hide yes)
			)
		)
		(property "Public" "False"
			(at 250.19 173.99 0)
			(effects
				(font
					(size 1.27 1.27)
				)
				(justify left bottom)
				(hide yes)
			)
		)
		(pin "1"
		)
		(pin "2"
		)
		(instances
			(project "cm4-baseboard"
				(path ""
					(reference "C404")
					(unit 1)
				)
			)
		)
	)
	(symbol
		(lib_id "antmicroModularConnectorsJacksWithMagnetics:Bus_RJ45_5-2337992-8")
		(at 185.42 50.8 0)
		(unit 1)
		(exclude_from_sim no)
		(in_bom yes)
		(on_board yes)
		(dnp no)
		(fields_autoplaced yes)
		(property "Reference" "J401"
			(at 196.215 43.18 0)
			(effects
				(font
					(size 1.27 1.27)
				)
			)
		)
		(property "Value" "Bus_RJ45_5-2337992-8"
			(at 196.215 45.72 0)
			(effects
				(font
					(size 1.27 1.27)
					(thickness 0.15)
				)
				(hide yes)
			)
		)
		(property "Footprint" "antmicro-footprints:RJ45_X-2337992-8_Horizontal"
			(at 220.98 58.42 0)
			(effects
				(font
					(size 1.27 1.27)
					(thickness 0.15)
				)
				(justify left bottom)
				(hide yes)
			)
		)
		(property "Datasheet" "https://www.te.com/commerce/DocumentDelivery/DDEController?Action=showdoc&DocId=Customer+Drawing%7F5-2337992-8%7FA%7Fpdf%7FEnglish%7FENG_CD_5-2337992-8_A.pdf%7F5-2337992-8"
			(at 220.98 60.96 0)
			(effects
				(font
					(size 1.27 1.27)
					(thickness 0.15)
				)
				(justify left bottom)
				(hide yes)
			)
		)
		(property "Description" ""
			(at 185.42 50.8 0)
			(effects
				(font
					(size 1.27 1.27)
				)
				(hide yes)
			)
		)
		(property "MPN" "5-2337992-8"
			(at 196.215 45.72 0)
			(effects
				(font
					(size 1.27 1.27)
					(thickness 0.15)
				)
			)
		)
		(property "Manufacturer" "TE Connectivity"
			(at 220.98 66.04 0)
			(effects
				(font
					(size 1.27 1.27)
					(thickness 0.15)
				)
				(justify left bottom)
				(hide yes)
			)
		)
		(property "Author" "Antmicro"
			(at 220.98 68.58 0)
			(effects
				(font
					(size 1.27 1.27)
					(thickness 0.15)
				)
				(justify left bottom)
				(hide yes)
			)
		)
		(property "License" "Apache-2.0"
			(at 220.98 71.12 0)
			(effects
				(font
					(size 1.27 1.27)
					(thickness 0.15)
				)
				(justify left bottom)
				(hide yes)
			)
		)
		(pin "1"
		)
		(pin "10"
		)
		(pin "11"
		)
		(pin "12"
		)
		(pin "13"
		)
		(pin "14"
		)
		(pin "15"
		)
		(pin "16"
		)
		(pin "17"
		)
		(pin "18"
		)
		(pin "19"
		)
		(pin "2"
		)
		(pin "20"
		)
		(pin "3"
		)
		(pin "4"
		)
		(pin "5"
		)
		(pin "6"
		)
		(pin "7"
		)
		(pin "8"
		)
		(pin "9"
		)
		(instances
			(project "cm4-baseboard"
				(path ""
					(reference "J401")
					(unit 1)
				)
			)
		)
	)
	(symbol
		(lib_id "antmicropower:GND")
		(at 209.55 95.25 0)
		(mirror y)
		(unit 1)
		(exclude_from_sim no)
		(in_bom yes)
		(on_board yes)
		(dnp no)
		(fields_autoplaced yes)
		(property "Reference" "#PWR0404"
			(at 209.55 101.6 0)
			(effects
				(font
					(size 1.27 1.27)
				)
				(justify left bottom)
				(hide yes)
			)
		)
		(property "Value" "GND"
			(at 209.55 100.33 0)
			(effects
				(font
					(size 1.27 1.27)
				)
			)
		)
		(property "Footprint" ""
			(at 200.66 102.87 0)
			(effects
				(font
					(size 1.27 1.27)
					(thickness 0.15)
				)
				(justify left bottom)
				(hide yes)
			)
		)
		(property "Datasheet" ""
			(at 200.66 107.95 0)
			(effects
				(font
					(size 1.27 1.27)
					(thickness 0.15)
				)
				(justify left bottom)
				(hide yes)
			)
		)
		(property "Description" ""
			(at 209.55 95.25 0)
			(effects
				(font
					(size 1.27 1.27)
				)
				(hide yes)
			)
		)
		(property "Author" "Antmicro"
			(at 200.66 102.87 0)
			(effects
				(font
					(size 1.27 1.27)
					(thickness 0.15)
				)
				(justify left bottom)
				(hide yes)
			)
		)
		(property "License" "Apache-2.0"
			(at 200.66 105.41 0)
			(effects
				(font
					(size 1.27 1.27)
					(thickness 0.15)
				)
				(justify left bottom)
				(hide yes)
			)
		)
		(pin "1"
		)
		(instances
			(project "cm4-baseboard"
				(path ""
					(reference "#PWR0404")
					(unit 1)
				)
			)
		)
	)
	(symbol
		(lib_id "antmicroResistors0402:R_10k_0402")
		(at 185.42 189.23 90)
		(unit 1)
		(exclude_from_sim no)
		(in_bom no)
		(on_board yes)
		(dnp yes)
		(property "Reference" "R407"
			(at 186.69 186.055 90)
			(effects
				(font
					(size 1.27 1.27)
				)
				(justify right)
			)
		)
		(property "Value" "R_10k_0402"
			(at 198.12 168.91 0)
			(effects
				(font
					(size 1.27 1.27)
					(thickness 0.15)
				)
				(justify left bottom)
				(hide yes)
			)
		)
		(property "Footprint" "antmicro-footprints:R_0402_1005Metric"
			(at 200.66 168.91 0)
			(effects
				(font
					(size 1.27 1.27)
					(thickness 0.15)
				)
				(justify left bottom)
				(hide yes)
			)
		)
		(property "Datasheet" "https://www.bourns.com/docs/product-datasheets/cr.pdf"
			(at 203.2 168.91 0)
			(effects
				(font
					(size 1.27 1.27)
					(thickness 0.15)
				)
				(justify left bottom)
				(hide yes)
			)
		)
		(property "Description" ""
			(at 185.42 189.23 0)
			(effects
				(font
					(size 1.27 1.27)
				)
				(hide yes)
			)
		)
		(property "Manufacturer" "Bourns"
			(at 208.28 168.91 0)
			(effects
				(font
					(size 1.27 1.27)
					(thickness 0.15)
				)
				(justify left bottom)
				(hide yes)
			)
		)
		(property "MPN" "CR0402-FX-1002GLF"
			(at 205.74 168.91 0)
			(effects
				(font
					(size 1.27 1.27)
					(thickness 0.15)
				)
				(justify left bottom)
				(hide yes)
			)
		)
		(property "Val" "10k"
			(at 186.69 187.96 90)
			(effects
				(font
					(size 1.27 1.27)
					(thickness 0.15)
				)
				(justify right)
			)
		)
		(property "License" "Apache-2.0"
			(at 210.82 168.91 0)
			(effects
				(font
					(size 1.27 1.27)
					(thickness 0.15)
				)
				(justify left bottom)
				(hide yes)
			)
		)
		(property "Author" "Antmicro"
			(at 213.36 168.91 0)
			(effects
				(font
					(size 1.27 1.27)
					(thickness 0.15)
				)
				(justify left bottom)
				(hide yes)
			)
		)
		(property "Tolerance" "1%"
			(at 195.58 168.91 0)
			(effects
				(font
					(size 1.27 1.27)
				)
				(justify left bottom)
				(hide yes)
			)
		)
		(pin "1"
		)
		(pin "2"
		)
		(instances
			(project "cm4-baseboard"
				(path ""
					(reference "R407")
					(unit 1)
				)
			)
		)
	)
	(symbol
		(lib_id "antmicroCapacitorsmisc:C_22u_25V_0805")
		(at 340.36 187.96 90)
		(mirror x)
		(unit 1)
		(exclude_from_sim no)
		(in_bom yes)
		(on_board yes)
		(dnp no)
		(property "Reference" "C408"
			(at 341.63 191.77 90)
			(effects
				(font
					(size 1.27 1.27)
				)
				(justify right)
			)
		)
		(property "Value" "C_22u_25V_0805"
			(at 344.17 187.96 0)
			(effects
				(font
					(size 1.27 1.27)
				)
				(justify left bottom)
				(hide yes)
			)
		)
		(property "Footprint" "antmicro-footprints:C_0805_2012Metric"
			(at 335.28 193.04 0)
			(effects
				(font
					(size 1.524 1.524)
				)
				(justify left bottom)
				(hide yes)
			)
		)
		(property "Datasheet" "https://product.samsungsem.com/mlcc/CL21A226MAYNNN.do"
			(at 340.36 187.96 0)
			(effects
				(font
					(size 1.27 1.27)
				)
				(justify left bottom)
				(hide yes)
			)
		)
		(property "Description" ""
			(at 340.36 187.96 0)
			(effects
				(font
					(size 1.27 1.27)
				)
				(hide yes)
			)
		)
		(property "Manufacturer" "Samsung Electro-Mechanics"
			(at 330.2 193.04 0)
			(effects
				(font
					(size 1.524 1.524)
				)
				(justify left bottom)
				(hide yes)
			)
		)
		(property "MPN" "CL21A226MAYNNNE"
			(at 332.74 193.04 0)
			(effects
				(font
					(size 1.524 1.524)
				)
				(justify left bottom)
				(hide yes)
			)
		)
		(property "Val" "22u"
			(at 341.63 194.31 90)
			(effects
				(font
					(size 1.27 1.27)
				)
				(justify right)
			)
		)
		(property "License" "Apache-2.0"
			(at 363.22 208.28 0)
			(effects
				(font
					(size 1.27 1.27)
					(thickness 0.15)
				)
				(justify left bottom)
				(hide yes)
			)
		)
		(property "Author" "Antmicro"
			(at 365.76 208.28 0)
			(effects
				(font
					(size 1.27 1.27)
					(thickness 0.15)
				)
				(justify left bottom)
				(hide yes)
			)
		)
		(property "Voltage" "25V"
			(at 341.63 196.85 90)
			(effects
				(font
					(size 1.27 1.27)
				)
				(justify right)
			)
		)
		(property "Dielectric" "X5R"
			(at 370.84 208.28 0)
			(effects
				(font
					(size 1.27 1.27)
				)
				(justify left bottom)
				(hide yes)
			)
		)
		(property "Public" "False"
			(at 373.38 208.28 0)
			(effects
				(font
					(size 1.27 1.27)
				)
				(justify left bottom)
				(hide yes)
			)
		)
		(pin "1"
		)
		(pin "2"
		)
		(instances
			(project "cm4-baseboard"
				(path ""
					(reference "C408")
					(unit 1)
				)
			)
		)
	)
	(symbol
		(lib_id "antmicroCapacitors0402:C_10n_0402")
		(at 181.61 88.9 270)
		(unit 1)
		(exclude_from_sim no)
		(in_bom yes)
		(on_board yes)
		(dnp no)
		(property "Reference" "C402"
			(at 187.96 90.17 90)
			(effects
				(font
					(size 1.27 1.27)
				)
				(justify right)
			)
		)
		(property "Value" "C_10n_0402"
			(at 171.45 109.22 0)
			(effects
				(font
					(size 1.27 1.27)
					(thickness 0.15)
				)
				(justify left bottom)
				(hide yes)
			)
		)
		(property "Footprint" "antmicro-footprints:C_0402_1005Metric"
			(at 168.91 109.22 0)
			(effects
				(font
					(size 1.27 1.27)
					(thickness 0.15)
				)
				(justify left bottom)
				(hide yes)
			)
		)
		(property "Datasheet" "https://www.murata.com/products/productdetail?partno=GRM155R71H103KA88%23"
			(at 166.37 109.22 0)
			(effects
				(font
					(size 1.27 1.27)
					(thickness 0.15)
				)
				(justify left bottom)
				(hide yes)
			)
		)
		(property "Description" ""
			(at 181.61 88.9 0)
			(effects
				(font
					(size 1.27 1.27)
				)
				(hide yes)
			)
		)
		(property "Manufacturer" "Murata"
			(at 161.29 109.22 0)
			(effects
				(font
					(size 1.27 1.27)
					(thickness 0.15)
				)
				(justify left bottom)
				(hide yes)
			)
		)
		(property "MPN" "GRM155R71H103KA88D"
			(at 163.83 109.22 0)
			(effects
				(font
					(size 1.27 1.27)
					(thickness 0.15)
				)
				(justify left bottom)
				(hide yes)
			)
		)
		(property "Val" "10n"
			(at 187.96 92.71 90)
			(effects
				(font
					(size 1.27 1.27)
					(thickness 0.15)
				)
				(justify right)
			)
		)
		(property "License" "Apache-2.0"
			(at 158.75 109.22 0)
			(effects
				(font
					(size 1.27 1.27)
					(thickness 0.15)
				)
				(justify left bottom)
				(hide yes)
			)
		)
		(property "Author" "Antmicro"
			(at 156.21 109.22 0)
			(effects
				(font
					(size 1.27 1.27)
					(thickness 0.15)
				)
				(justify left bottom)
				(hide yes)
			)
		)
		(property "Voltage" "50V"
			(at 153.67 109.22 0)
			(effects
				(font
					(size 1.27 1.27)
				)
				(justify left bottom)
				(hide yes)
			)
		)
		(property "Dielectric" "X7R"
			(at 151.13 109.22 0)
			(effects
				(font
					(size 1.27 1.27)
				)
				(justify left bottom)
				(hide yes)
			)
		)
		(pin "1"
		)
		(pin "2"
		)
		(instances
			(project "cm4-baseboard"
				(path ""
					(reference "C402")
					(unit 1)
				)
			)
		)
	)
	(symbol
		(lib_id "antmicropower:GND")
		(at 306.07 237.49 0)
		(unit 1)
		(exclude_from_sim no)
		(in_bom yes)
		(on_board yes)
		(dnp no)
		(fields_autoplaced yes)
		(property "Reference" "#PWR0416"
			(at 306.07 243.84 0)
			(effects
				(font
					(size 1.27 1.27)
				)
				(justify left bottom)
				(hide yes)
			)
		)
		(property "Value" "GND"
			(at 306.07 242.57 0)
			(effects
				(font
					(size 1.27 1.27)
				)
			)
		)
		(property "Footprint" ""
			(at 314.96 245.11 0)
			(effects
				(font
					(size 1.27 1.27)
					(thickness 0.15)
				)
				(justify left bottom)
				(hide yes)
			)
		)
		(property "Datasheet" ""
			(at 314.96 250.19 0)
			(effects
				(font
					(size 1.27 1.27)
					(thickness 0.15)
				)
				(justify left bottom)
				(hide yes)
			)
		)
		(property "Description" ""
			(at 306.07 237.49 0)
			(effects
				(font
					(size 1.27 1.27)
				)
				(hide yes)
			)
		)
		(property "Author" "Antmicro"
			(at 314.96 245.11 0)
			(effects
				(font
					(size 1.27 1.27)
					(thickness 0.15)
				)
				(justify left bottom)
				(hide yes)
			)
		)
		(property "License" "Apache-2.0"
			(at 314.96 247.65 0)
			(effects
				(font
					(size 1.27 1.27)
					(thickness 0.15)
				)
				(justify left bottom)
				(hide yes)
			)
		)
		(pin "1"
		)
		(instances
			(project "cm4-baseboard"
				(path ""
					(reference "#PWR0416")
					(unit 1)
				)
			)
		)
	)
	(symbol
		(lib_id "antmicropower:GNDD")
		(at 287.02 217.17 0)
		(unit 1)
		(exclude_from_sim no)
		(in_bom yes)
		(on_board yes)
		(dnp no)
		(fields_autoplaced yes)
		(property "Reference" "#PWR0414"
			(at 287.02 223.52 0)
			(effects
				(font
					(size 1.27 1.27)
				)
				(justify left bottom)
				(hide yes)
			)
		)
		(property "Value" "GNDD"
			(at 287.02 221.615 0)
			(effects
				(font
					(size 1.27 1.27)
				)
			)
		)
		(property "Footprint" ""
			(at 287.02 217.17 0)
			(effects
				(font
					(size 1.27 1.27)
				)
				(hide yes)
			)
		)
		(property "Datasheet" ""
			(at 287.02 217.17 0)
			(effects
				(font
					(size 1.27 1.27)
				)
				(hide yes)
			)
		)
		(property "Description" ""
			(at 287.02 217.17 0)
			(effects
				(font
					(size 1.27 1.27)
				)
				(hide yes)
			)
		)
		(property "Author" "Antmicro"
			(at 302.26 224.79 0)
			(effects
				(font
					(size 1.27 1.27)
					(thickness 0.15)
				)
				(justify left bottom)
				(hide yes)
			)
		)
		(property "License" "Apache-2.0"
			(at 302.26 227.33 0)
			(effects
				(font
					(size 1.27 1.27)
					(thickness 0.15)
				)
				(justify left bottom)
				(hide yes)
			)
		)
		(pin "1"
		)
		(instances
			(project "cm4-baseboard"
				(path ""
					(reference "#PWR0414")
					(unit 1)
				)
			)
		)
	)
	(symbol
		(lib_id "antmicroResistors0402:R_100k_0402")
		(at 266.7 215.9 90)
		(unit 1)
		(exclude_from_sim no)
		(in_bom yes)
		(on_board yes)
		(dnp no)
		(fields_autoplaced yes)
		(property "Reference" "R416"
			(at 269.24 212.0899 90)
			(effects
				(font
					(size 1.27 1.27)
				)
				(justify right)
			)
		)
		(property "Value" "R_100k_0402"
			(at 279.4 195.58 0)
			(effects
				(font
					(size 1.27 1.27)
					(thickness 0.15)
				)
				(justify left bottom)
				(hide yes)
			)
		)
		(property "Footprint" "antmicro-footprints:R_0402_1005Metric"
			(at 281.94 195.58 0)
			(effects
				(font
					(size 1.27 1.27)
					(thickness 0.15)
				)
				(justify left bottom)
				(hide yes)
			)
		)
		(property "Datasheet" "https://www.bourns.com/docs/product-datasheets/cr.pdf"
			(at 284.48 195.58 0)
			(effects
				(font
					(size 1.27 1.27)
					(thickness 0.15)
				)
				(justify left bottom)
				(hide yes)
			)
		)
		(property "Description" ""
			(at 266.7 215.9 0)
			(effects
				(font
					(size 1.27 1.27)
				)
				(hide yes)
			)
		)
		(property "Manufacturer" "Bourns"
			(at 289.56 195.58 0)
			(effects
				(font
					(size 1.27 1.27)
					(thickness 0.15)
				)
				(justify left bottom)
				(hide yes)
			)
		)
		(property "MPN" "CR0402-FX-1003GLF"
			(at 287.02 195.58 0)
			(effects
				(font
					(size 1.27 1.27)
					(thickness 0.15)
				)
				(justify left bottom)
				(hide yes)
			)
		)
		(property "Val" "100k"
			(at 269.24 214.6299 90)
			(effects
				(font
					(size 1.27 1.27)
					(thickness 0.15)
				)
				(justify right)
			)
		)
		(property "License" "Apache-2.0"
			(at 292.1 195.58 0)
			(effects
				(font
					(size 1.27 1.27)
					(thickness 0.15)
				)
				(justify left bottom)
				(hide yes)
			)
		)
		(property "Author" "Antmicro"
			(at 294.64 195.58 0)
			(effects
				(font
					(size 1.27 1.27)
					(thickness 0.15)
				)
				(justify left bottom)
				(hide yes)
			)
		)
		(property "Tolerance" "1%"
			(at 276.86 195.58 0)
			(effects
				(font
					(size 1.27 1.27)
				)
				(justify left bottom)
				(hide yes)
			)
		)
		(pin "1"
		)
		(pin "2"
		)
		(instances
			(project "cm4-baseboard"
				(path ""
					(reference "R416")
					(unit 1)
				)
			)
		)
	)
	(symbol
		(lib_id "antmicroResistors0402:R_10k_0402")
		(at 185.42 213.36 180)
		(unit 1)
		(exclude_from_sim no)
		(in_bom yes)
		(on_board yes)
		(dnp no)
		(property "Reference" "R408"
			(at 182.88 209.55 0)
			(effects
				(font
					(size 1.27 1.27)
				)
			)
		)
		(property "Value" "R_10k_0402"
			(at 165.1 200.66 0)
			(effects
				(font
					(size 1.27 1.27)
					(thickness 0.15)
				)
				(justify left bottom)
				(hide yes)
			)
		)
		(property "Footprint" "antmicro-footprints:R_0402_1005Metric"
			(at 165.1 198.12 0)
			(effects
				(font
					(size 1.27 1.27)
					(thickness 0.15)
				)
				(justify left bottom)
				(hide yes)
			)
		)
		(property "Datasheet" "https://www.bourns.com/docs/product-datasheets/cr.pdf"
			(at 165.1 195.58 0)
			(effects
				(font
					(size 1.27 1.27)
					(thickness 0.15)
				)
				(justify left bottom)
				(hide yes)
			)
		)
		(property "Description" ""
			(at 185.42 213.36 0)
			(effects
				(font
					(size 1.27 1.27)
				)
				(hide yes)
			)
		)
		(property "Manufacturer" "Bourns"
			(at 165.1 190.5 0)
			(effects
				(font
					(size 1.27 1.27)
					(thickness 0.15)
				)
				(justify left bottom)
				(hide yes)
			)
		)
		(property "MPN" "CR0402-FX-1002GLF"
			(at 165.1 193.04 0)
			(effects
				(font
					(size 1.27 1.27)
					(thickness 0.15)
				)
				(justify left bottom)
				(hide yes)
			)
		)
		(property "Val" "10k"
			(at 182.88 211.455 0)
			(effects
				(font
					(size 1.27 1.27)
					(thickness 0.15)
				)
			)
		)
		(property "License" "Apache-2.0"
			(at 165.1 187.96 0)
			(effects
				(font
					(size 1.27 1.27)
					(thickness 0.15)
				)
				(justify left bottom)
				(hide yes)
			)
		)
		(property "Author" "Antmicro"
			(at 165.1 185.42 0)
			(effects
				(font
					(size 1.27 1.27)
					(thickness 0.15)
				)
				(justify left bottom)
				(hide yes)
			)
		)
		(property "Tolerance" "1%"
			(at 165.1 203.2 0)
			(effects
				(font
					(size 1.27 1.27)
				)
				(justify left bottom)
				(hide yes)
			)
		)
		(pin "1"
		)
		(pin "2"
		)
		(instances
			(project "cm4-baseboard"
				(path ""
					(reference "R408")
					(unit 1)
				)
			)
		)
	)
	(symbol
		(lib_id "antmicroFerriteBeadsandChips:FB_220Z_2.2A_TDK-MPZ_0603")
		(at 97.79 182.88 0)
		(unit 1)
		(exclude_from_sim no)
		(in_bom yes)
		(on_board yes)
		(dnp no)
		(fields_autoplaced yes)
		(property "Reference" "FB401"
			(at 100.2919 176.53 0)
			(effects
				(font
					(size 1.27 1.27)
				)
			)
		)
		(property "Value" "FB_220Z_2.2A_TDK-MPZ_0603"
			(at 100.2919 179.07 0)
			(effects
				(font
					(size 1.27 1.27)
					(thickness 0.15)
				)
				(hide yes)
			)
		)
		(property "Footprint" "antmicro-footprints:FB_0603_1608Metric"
			(at 111.76 187.96 0)
			(effects
				(font
					(size 1.27 1.27)
					(thickness 0.15)
				)
				(justify left bottom)
				(hide yes)
			)
		)
		(property "Datasheet" "https://product.tdk.com/info/en/catalog/datasheets/beads_commercial_power_mpz1608_en.pdf"
			(at 111.76 190.5 0)
			(effects
				(font
					(size 1.27 1.27)
					(thickness 0.15)
				)
				(justify left bottom)
				(hide yes)
			)
		)
		(property "Description" ""
			(at 97.79 182.88 0)
			(effects
				(font
					(size 1.27 1.27)
				)
				(hide yes)
			)
		)
		(property "MPN" "MPZ1608S221ATA00"
			(at 111.76 193.04 0)
			(effects
				(font
					(size 1.27 1.27)
					(thickness 0.15)
				)
				(justify left bottom)
				(hide yes)
			)
		)
		(property "Manufacturer" "TDK"
			(at 111.76 195.58 0)
			(effects
				(font
					(size 1.27 1.27)
					(thickness 0.15)
				)
				(justify left bottom)
				(hide yes)
			)
		)
		(property "Author" "Antmicro"
			(at 111.76 198.12 0)
			(effects
				(font
					(size 1.27 1.27)
					(thickness 0.15)
				)
				(justify left bottom)
				(hide yes)
			)
		)
		(property "License" "Apache-2.0"
			(at 111.76 200.66 0)
			(effects
				(font
					(size 1.27 1.27)
					(thickness 0.15)
				)
				(justify left bottom)
				(hide yes)
			)
		)
		(property "Val" "220Z/2.2A"
			(at 100.2919 179.07 0)
			(effects
				(font
					(size 1.27 1.27)
				)
			)
		)
		(property "Current" ""
			(at 0 365.76 0)
			(effects
				(font
					(size 1.27 1.27)
				)
				(hide yes)
			)
		)
		(pin "1"
		)
		(pin "2"
		)
		(instances
			(project "cm4-baseboard"
				(path ""
					(reference "FB401")
					(unit 1)
				)
			)
		)
	)
	(symbol
		(lib_id "antmicroOptoisolatorsLogicOutput:ACPL-217-500E")
		(at 298.45 232.41 0)
		(mirror y)
		(unit 1)
		(exclude_from_sim no)
		(in_bom yes)
		(on_board yes)
		(dnp no)
		(fields_autoplaced yes)
		(property "Reference" "U402"
			(at 291.973 240.03 0)
			(effects
				(font
					(size 1.27 1.27)
					(thickness 0.15)
				)
			)
		)
		(property "Value" "ACPL-217-500E"
			(at 291.973 242.57 0)
			(effects
				(font
					(size 1.27 1.27)
					(thickness 0.15)
				)
				(hide yes)
			)
		)
		(property "Footprint" "antmicro-footprints:SOIC-4_4.55x2.6mm_P1.27mm"
			(at 270.51 242.57 0)
			(effects
				(font
					(size 1.27 1.27)
					(thickness 0.15)
				)
				(justify left bottom)
				(hide yes)
			)
		)
		(property "Datasheet" "https://docs.broadcom.com/doc/AV02-0470EN"
			(at 270.51 245.11 0)
			(effects
				(font
					(size 1.27 1.27)
					(thickness 0.15)
				)
				(justify left bottom)
				(hide yes)
			)
		)
		(property "Description" "Broadcom ACPL-217-500E DC Input Transistor Output Optocoupler, Surface Mount, 4-Pin SO"
			(at 270.51 247.65 0)
			(effects
				(font
					(size 1.27 1.27)
					(thickness 0.15)
				)
				(justify left bottom)
				(hide yes)
			)
		)
		(property "Manufacturer" "Broadcom"
			(at 270.51 250.19 0)
			(effects
				(font
					(size 1.27 1.27)
					(thickness 0.15)
				)
				(justify left bottom)
				(hide yes)
			)
		)
		(property "MPN" "ACPL-217-500E"
			(at 291.973 242.57 0)
			(effects
				(font
					(size 1.27 1.27)
					(thickness 0.15)
				)
			)
		)
		(property "Author" "Antmicro"
			(at 270.51 255.27 0)
			(effects
				(font
					(size 1.27 1.27)
					(thickness 0.15)
				)
				(justify left bottom)
				(hide yes)
			)
		)
		(property "License" "Apache-2.0"
			(at 270.51 257.81 0)
			(effects
				(font
					(size 1.27 1.27)
					(thickness 0.15)
				)
				(justify left bottom)
				(hide yes)
			)
		)
		(pin "1"
		)
		(pin "2"
		)
		(pin "3"
		)
		(pin "4"
		)
		(instances
			(project "cm4-baseboard"
				(path ""
					(reference "U402")
					(unit 1)
				)
			)
		)
	)
	(symbol
		(lib_id "antmicropower:GNDD")
		(at 217.17 201.93 0)
		(unit 1)
		(exclude_from_sim no)
		(in_bom yes)
		(on_board yes)
		(dnp no)
		(fields_autoplaced yes)
		(property "Reference" "#PWR0405"
			(at 217.17 208.28 0)
			(effects
				(font
					(size 1.27 1.27)
				)
				(justify left bottom)
				(hide yes)
			)
		)
		(property "Value" "GNDD"
			(at 217.17 206.375 0)
			(effects
				(font
					(size 1.27 1.27)
				)
			)
		)
		(property "Footprint" ""
			(at 217.17 201.93 0)
			(effects
				(font
					(size 1.27 1.27)
				)
				(hide yes)
			)
		)
		(property "Datasheet" ""
			(at 217.17 201.93 0)
			(effects
				(font
					(size 1.27 1.27)
				)
				(hide yes)
			)
		)
		(property "Description" ""
			(at 217.17 201.93 0)
			(effects
				(font
					(size 1.27 1.27)
				)
				(hide yes)
			)
		)
		(property "Author" "Antmicro"
			(at 232.41 209.55 0)
			(effects
				(font
					(size 1.27 1.27)
					(thickness 0.15)
				)
				(justify left bottom)
				(hide yes)
			)
		)
		(property "License" "Apache-2.0"
			(at 232.41 212.09 0)
			(effects
				(font
					(size 1.27 1.27)
					(thickness 0.15)
				)
				(justify left bottom)
				(hide yes)
			)
		)
		(pin "1"
		)
		(instances
			(project "cm4-baseboard"
				(path ""
					(reference "#PWR0405")
					(unit 1)
				)
			)
		)
	)
	(symbol
		(lib_id "antmicroResistors0402:R_200R_0402")
		(at 218.44 93.98 270)
		(mirror x)
		(unit 1)
		(exclude_from_sim no)
		(in_bom yes)
		(on_board yes)
		(dnp no)
		(fields_autoplaced yes)
		(property "Reference" "R413"
			(at 220.98 90.1699 90)
			(effects
				(font
					(size 1.27 1.27)
				)
				(justify left)
			)
		)
		(property "Value" "R_200R_0402"
			(at 205.74 73.66 0)
			(effects
				(font
					(size 1.27 1.27)
					(thickness 0.15)
				)
				(justify left bottom)
				(hide yes)
			)
		)
		(property "Footprint" "antmicro-footprints:R_0402_1005Metric"
			(at 203.2 73.66 0)
			(effects
				(font
					(size 1.27 1.27)
					(thickness 0.15)
				)
				(justify left bottom)
				(hide yes)
			)
		)
		(property "Datasheet" "https://www.bourns.com/docs/product-datasheets/cr.pdf"
			(at 200.66 73.66 0)
			(effects
				(font
					(size 1.27 1.27)
					(thickness 0.15)
				)
				(justify left bottom)
				(hide yes)
			)
		)
		(property "Description" ""
			(at 218.44 93.98 0)
			(effects
				(font
					(size 1.27 1.27)
				)
				(hide yes)
			)
		)
		(property "Manufacturer" "Bourns"
			(at 195.58 73.66 0)
			(effects
				(font
					(size 1.27 1.27)
					(thickness 0.15)
				)
				(justify left bottom)
				(hide yes)
			)
		)
		(property "MPN" "CR0402-FX-2000GLF"
			(at 198.12 73.66 0)
			(effects
				(font
					(size 1.27 1.27)
					(thickness 0.15)
				)
				(justify left bottom)
				(hide yes)
			)
		)
		(property "Val" "200R"
			(at 220.98 92.7099 90)
			(effects
				(font
					(size 1.27 1.27)
					(thickness 0.15)
				)
				(justify left)
			)
		)
		(property "License" "Apache-2.0"
			(at 193.04 73.66 0)
			(effects
				(font
					(size 1.27 1.27)
					(thickness 0.15)
				)
				(justify left bottom)
				(hide yes)
			)
		)
		(property "Author" "Antmicro"
			(at 190.5 73.66 0)
			(effects
				(font
					(size 1.27 1.27)
					(thickness 0.15)
				)
				(justify left bottom)
				(hide yes)
			)
		)
		(property "Tolerance" "1%"
			(at 208.28 73.66 0)
			(effects
				(font
					(size 1.27 1.27)
				)
				(justify left bottom)
				(hide yes)
			)
		)
		(pin "1"
		)
		(pin "2"
		)
		(instances
			(project "cm4-baseboard"
				(path ""
					(reference "R413")
					(unit 1)
				)
			)
		)
	)
	(symbol
		(lib_id "antmicroResistors0402:R_10k_0402")
		(at 195.58 189.23 90)
		(unit 1)
		(exclude_from_sim no)
		(in_bom no)
		(on_board yes)
		(dnp yes)
		(property "Reference" "R409"
			(at 196.85 186.055 90)
			(effects
				(font
					(size 1.27 1.27)
				)
				(justify right)
			)
		)
		(property "Value" "R_10k_0402"
			(at 208.28 168.91 0)
			(effects
				(font
					(size 1.27 1.27)
					(thickness 0.15)
				)
				(justify left bottom)
				(hide yes)
			)
		)
		(property "Footprint" "antmicro-footprints:R_0402_1005Metric"
			(at 210.82 168.91 0)
			(effects
				(font
					(size 1.27 1.27)
					(thickness 0.15)
				)
				(justify left bottom)
				(hide yes)
			)
		)
		(property "Datasheet" "https://www.bourns.com/docs/product-datasheets/cr.pdf"
			(at 213.36 168.91 0)
			(effects
				(font
					(size 1.27 1.27)
					(thickness 0.15)
				)
				(justify left bottom)
				(hide yes)
			)
		)
		(property "Description" ""
			(at 195.58 189.23 0)
			(effects
				(font
					(size 1.27 1.27)
				)
				(hide yes)
			)
		)
		(property "Manufacturer" "Bourns"
			(at 218.44 168.91 0)
			(effects
				(font
					(size 1.27 1.27)
					(thickness 0.15)
				)
				(justify left bottom)
				(hide yes)
			)
		)
		(property "MPN" "CR0402-FX-1002GLF"
			(at 215.9 168.91 0)
			(effects
				(font
					(size 1.27 1.27)
					(thickness 0.15)
				)
				(justify left bottom)
				(hide yes)
			)
		)
		(property "Val" "10k"
			(at 196.85 187.96 90)
			(effects
				(font
					(size 1.27 1.27)
					(thickness 0.15)
				)
				(justify right)
			)
		)
		(property "License" "Apache-2.0"
			(at 220.98 168.91 0)
			(effects
				(font
					(size 1.27 1.27)
					(thickness 0.15)
				)
				(justify left bottom)
				(hide yes)
			)
		)
		(property "Author" "Antmicro"
			(at 223.52 168.91 0)
			(effects
				(font
					(size 1.27 1.27)
					(thickness 0.15)
				)
				(justify left bottom)
				(hide yes)
			)
		)
		(property "Tolerance" "1%"
			(at 205.74 168.91 0)
			(effects
				(font
					(size 1.27 1.27)
				)
				(justify left bottom)
				(hide yes)
			)
		)
		(pin "1"
		)
		(pin "2"
		)
		(instances
			(project "cm4-baseboard"
				(path ""
					(reference "R409")
					(unit 1)
				)
			)
		)
	)
	(symbol
		(lib_id "antmicroResistors0402:R_24k9_0402")
		(at 247.65 190.5 90)
		(unit 1)
		(exclude_from_sim no)
		(in_bom yes)
		(on_board yes)
		(dnp no)
		(fields_autoplaced yes)
		(property "Reference" "R414"
			(at 250.19 186.6899 90)
			(effects
				(font
					(size 1.27 1.27)
				)
				(justify right)
			)
		)
		(property "Value" "R_24k9_0402"
			(at 260.35 170.18 0)
			(effects
				(font
					(size 1.27 1.27)
					(thickness 0.15)
				)
				(justify left bottom)
				(hide yes)
			)
		)
		(property "Footprint" "antmicro-footprints:R_0402_1005Metric"
			(at 262.89 170.18 0)
			(effects
				(font
					(size 1.27 1.27)
					(thickness 0.15)
				)
				(justify left bottom)
				(hide yes)
			)
		)
		(property "Datasheet" "https://www.bourns.com/docs/product-datasheets/cr.pdf"
			(at 265.43 170.18 0)
			(effects
				(font
					(size 1.27 1.27)
					(thickness 0.15)
				)
				(justify left bottom)
				(hide yes)
			)
		)
		(property "Description" ""
			(at 247.65 190.5 0)
			(effects
				(font
					(size 1.27 1.27)
				)
				(hide yes)
			)
		)
		(property "Manufacturer" "Bourns"
			(at 270.51 170.18 0)
			(effects
				(font
					(size 1.27 1.27)
					(thickness 0.15)
				)
				(justify left bottom)
				(hide yes)
			)
		)
		(property "MPN" "CR0402-FX-2492GLF"
			(at 267.97 170.18 0)
			(effects
				(font
					(size 1.27 1.27)
					(thickness 0.15)
				)
				(justify left bottom)
				(hide yes)
			)
		)
		(property "Val" "24k9"
			(at 250.19 189.2299 90)
			(effects
				(font
					(size 1.27 1.27)
					(thickness 0.15)
				)
				(justify right)
			)
		)
		(property "License" "Apache-2.0"
			(at 273.05 170.18 0)
			(effects
				(font
					(size 1.27 1.27)
					(thickness 0.15)
				)
				(justify left bottom)
				(hide yes)
			)
		)
		(property "Author" "Antmicro"
			(at 275.59 170.18 0)
			(effects
				(font
					(size 1.27 1.27)
					(thickness 0.15)
				)
				(justify left bottom)
				(hide yes)
			)
		)
		(property "Tolerance" "1%"
			(at 257.81 170.18 0)
			(effects
				(font
					(size 1.27 1.27)
				)
				(justify left bottom)
				(hide yes)
			)
		)
		(pin "1"
		)
		(pin "2"
		)
		(instances
			(project "cm4-baseboard"
				(path ""
					(reference "R414")
					(unit 1)
				)
			)
		)
	)
	(symbol
		(lib_id "antmicroTVSDiodes:PTVS58VS1UR,115")
		(at 113.03 190.5 90)
		(mirror x)
		(unit 1)
		(exclude_from_sim no)
		(in_bom yes)
		(on_board yes)
		(dnp no)
		(property "Reference" "D403"
			(at 110.49 191.77 90)
			(effects
				(font
					(size 1.27 1.27)
				)
				(justify left)
			)
		)
		(property "Value" "PTVS58VS1UR,115"
			(at 109.22 193.3576 90)
			(effects
				(font
					(size 1.27 1.27)
					(thickness 0.15)
				)
				(justify left)
				(hide yes)
			)
		)
		(property "Footprint" "antmicro-footprints:D_SOD-123F"
			(at 123.19 212.09 0)
			(effects
				(font
					(size 1.27 1.27)
					(thickness 0.15)
				)
				(justify left bottom)
				(hide yes)
			)
		)
		(property "Datasheet" "https://assets.nexperia.com/documents/data-sheet/PTVSXS1UR_SER.pdf"
			(at 125.73 212.09 0)
			(effects
				(font
					(size 1.27 1.27)
					(thickness 0.15)
				)
				(justify left bottom)
				(hide yes)
			)
		)
		(property "Description" ""
			(at 113.03 190.5 0)
			(effects
				(font
					(size 1.27 1.27)
				)
				(hide yes)
			)
		)
		(property "MPN" "PTVS58VS1UR,115"
			(at 110.49 194.31 90)
			(effects
				(font
					(size 1.27 1.27)
					(thickness 0.15)
				)
				(justify left)
			)
		)
		(property "Manufacturer" "Nexperia"
			(at 130.81 212.09 0)
			(effects
				(font
					(size 1.27 1.27)
					(thickness 0.15)
				)
				(justify left bottom)
				(hide yes)
			)
		)
		(property "Author" "Antmicro"
			(at 133.35 212.09 0)
			(effects
				(font
					(size 1.27 1.27)
					(thickness 0.15)
				)
				(justify left bottom)
				(hide yes)
			)
		)
		(property "License" "Apache-2.0"
			(at 135.89 212.09 0)
			(effects
				(font
					(size 1.27 1.27)
					(thickness 0.15)
				)
				(justify left bottom)
				(hide yes)
			)
		)
		(pin "2"
		)
		(pin "1"
		)
		(instances
			(project "cm4-baseboard"
				(path ""
					(reference "D403")
					(unit 1)
				)
			)
		)
	)
	(symbol
		(lib_id "antmicroResistors0402:R_10k_0402")
		(at 204.47 189.23 90)
		(unit 1)
		(exclude_from_sim no)
		(in_bom no)
		(on_board yes)
		(dnp yes)
		(property "Reference" "R410"
			(at 205.74 186.055 90)
			(effects
				(font
					(size 1.27 1.27)
				)
				(justify right)
			)
		)
		(property "Value" "R_10k_0402"
			(at 217.17 168.91 0)
			(effects
				(font
					(size 1.27 1.27)
					(thickness 0.15)
				)
				(justify left bottom)
				(hide yes)
			)
		)
		(property "Footprint" "antmicro-footprints:R_0402_1005Metric"
			(at 219.71 168.91 0)
			(effects
				(font
					(size 1.27 1.27)
					(thickness 0.15)
				)
				(justify left bottom)
				(hide yes)
			)
		)
		(property "Datasheet" "https://www.bourns.com/docs/product-datasheets/cr.pdf"
			(at 222.25 168.91 0)
			(effects
				(font
					(size 1.27 1.27)
					(thickness 0.15)
				)
				(justify left bottom)
				(hide yes)
			)
		)
		(property "Description" ""
			(at 204.47 189.23 0)
			(effects
				(font
					(size 1.27 1.27)
				)
				(hide yes)
			)
		)
		(property "Manufacturer" "Bourns"
			(at 227.33 168.91 0)
			(effects
				(font
					(size 1.27 1.27)
					(thickness 0.15)
				)
				(justify left bottom)
				(hide yes)
			)
		)
		(property "MPN" "CR0402-FX-1002GLF"
			(at 224.79 168.91 0)
			(effects
				(font
					(size 1.27 1.27)
					(thickness 0.15)
				)
				(justify left bottom)
				(hide yes)
			)
		)
		(property "Val" "10k"
			(at 205.74 187.96 90)
			(effects
				(font
					(size 1.27 1.27)
					(thickness 0.15)
				)
				(justify right)
			)
		)
		(property "License" "Apache-2.0"
			(at 229.87 168.91 0)
			(effects
				(font
					(size 1.27 1.27)
					(thickness 0.15)
				)
				(justify left bottom)
				(hide yes)
			)
		)
		(property "Author" "Antmicro"
			(at 232.41 168.91 0)
			(effects
				(font
					(size 1.27 1.27)
					(thickness 0.15)
				)
				(justify left bottom)
				(hide yes)
			)
		)
		(property "Tolerance" "1%"
			(at 214.63 168.91 0)
			(effects
				(font
					(size 1.27 1.27)
				)
				(justify left bottom)
				(hide yes)
			)
		)
		(pin "1"
		)
		(pin "2"
		)
		(instances
			(project "cm4-baseboard"
				(path ""
					(reference "R410")
					(unit 1)
				)
			)
		)
	)
	(symbol
		(lib_id "antmicroResistors0603:R_63R4_0603")
		(at 140.97 209.55 270)
		(mirror x)
		(unit 1)
		(exclude_from_sim no)
		(in_bom yes)
		(on_board yes)
		(dnp no)
		(fields_autoplaced yes)
		(property "Reference" "R404"
			(at 138.43 205.7399 90)
			(effects
				(font
					(size 1.27 1.27)
				)
				(justify right)
			)
		)
		(property "Value" "R_63R4_0603"
			(at 128.27 189.23 0)
			(effects
				(font
					(size 1.27 1.27)
					(thickness 0.15)
				)
				(justify left bottom)
				(hide yes)
			)
		)
		(property "Footprint" "antmicro-footprints:R_0603_1608Metric"
			(at 125.73 189.23 0)
			(effects
				(font
					(size 1.27 1.27)
					(thickness 0.15)
				)
				(justify left bottom)
				(hide yes)
			)
		)
		(property "Datasheet" "https://www.bourns.com/docs/product-datasheets/cr.pdf"
			(at 123.19 189.23 0)
			(effects
				(font
					(size 1.27 1.27)
					(thickness 0.15)
				)
				(justify left bottom)
				(hide yes)
			)
		)
		(property "Description" ""
			(at 140.97 209.55 0)
			(effects
				(font
					(size 1.27 1.27)
				)
				(hide yes)
			)
		)
		(property "Manufacturer" "Bourns"
			(at 118.11 189.23 0)
			(effects
				(font
					(size 1.27 1.27)
					(thickness 0.15)
				)
				(justify left bottom)
				(hide yes)
			)
		)
		(property "MPN" "CR0603-FX-63R4ELF"
			(at 120.65 189.23 0)
			(effects
				(font
					(size 1.27 1.27)
					(thickness 0.15)
				)
				(justify left bottom)
				(hide yes)
			)
		)
		(property "Val" "63R4"
			(at 138.43 208.2799 90)
			(effects
				(font
					(size 1.27 1.27)
					(thickness 0.15)
				)
				(justify right)
			)
		)
		(property "License" "Apache-2.0"
			(at 115.57 189.23 0)
			(effects
				(font
					(size 1.27 1.27)
					(thickness 0.15)
				)
				(justify left bottom)
				(hide yes)
			)
		)
		(property "Author" "Antmicro"
			(at 113.03 189.23 0)
			(effects
				(font
					(size 1.27 1.27)
					(thickness 0.15)
				)
				(justify left bottom)
				(hide yes)
			)
		)
		(property "Tolerance" "1%"
			(at 130.81 189.23 0)
			(effects
				(font
					(size 1.27 1.27)
				)
				(justify left bottom)
				(hide yes)
			)
		)
		(pin "1"
		)
		(pin "2"
		)
		(instances
			(project "cm4-baseboard"
				(path ""
					(reference "R404")
					(unit 1)
				)
			)
		)
	)
	(symbol
		(lib_id "antmicroCapacitors0402:C_100n_0402")
		(at 209.55 88.9 90)
		(mirror x)
		(unit 1)
		(exclude_from_sim no)
		(in_bom yes)
		(on_board yes)
		(dnp no)
		(fields_autoplaced yes)
		(property "Reference" "C403"
			(at 212.09 90.1762 90)
			(effects
				(font
					(size 1.27 1.27)
				)
				(justify right)
			)
		)
		(property "Value" "C_100n_0402"
			(at 219.71 109.22 0)
			(effects
				(font
					(size 1.27 1.27)
					(thickness 0.15)
				)
				(justify left bottom)
				(hide yes)
			)
		)
		(property "Footprint" "antmicro-footprints:C_0402_1005Metric"
			(at 222.25 109.22 0)
			(effects
				(font
					(size 1.27 1.27)
					(thickness 0.15)
				)
				(justify left bottom)
				(hide yes)
			)
		)
		(property "Datasheet" "https://www.murata.com/products/productdetail?partno=GRM155R61H104KE14%23"
			(at 224.79 109.22 0)
			(effects
				(font
					(size 1.27 1.27)
					(thickness 0.15)
				)
				(justify left bottom)
				(hide yes)
			)
		)
		(property "Description" ""
			(at 209.55 88.9 0)
			(effects
				(font
					(size 1.27 1.27)
				)
				(hide yes)
			)
		)
		(property "Manufacturer" "Murata"
			(at 229.87 109.22 0)
			(effects
				(font
					(size 1.27 1.27)
					(thickness 0.15)
				)
				(justify left bottom)
				(hide yes)
			)
		)
		(property "MPN" "GRM155R61H104KE14D"
			(at 227.33 109.22 0)
			(effects
				(font
					(size 1.27 1.27)
					(thickness 0.15)
				)
				(justify left bottom)
				(hide yes)
			)
		)
		(property "Val" "100n"
			(at 212.09 92.7162 90)
			(effects
				(font
					(size 1.27 1.27)
					(thickness 0.15)
				)
				(justify right)
			)
		)
		(property "License" "Apache-2.0"
			(at 232.41 109.22 0)
			(effects
				(font
					(size 1.27 1.27)
					(thickness 0.15)
				)
				(justify left bottom)
				(hide yes)
			)
		)
		(property "Author" "Antmicro"
			(at 234.95 109.22 0)
			(effects
				(font
					(size 1.27 1.27)
					(thickness 0.15)
				)
				(justify left bottom)
				(hide yes)
			)
		)
		(property "Voltage" "50V"
			(at 237.49 109.22 0)
			(effects
				(font
					(size 1.27 1.27)
				)
				(justify left bottom)
				(hide yes)
			)
		)
		(property "Dielectric" "X5R"
			(at 240.03 109.22 0)
			(effects
				(font
					(size 1.27 1.27)
				)
				(justify left bottom)
				(hide yes)
			)
		)
		(pin "1"
		)
		(pin "2"
		)
		(instances
			(project "cm4-baseboard"
				(path ""
					(reference "C403")
					(unit 1)
				)
			)
		)
	)
	(symbol
		(lib_id "antmicroCapacitorsmisc:C_100n_100V_0805")
		(at 118.11 195.58 90)
		(unit 1)
		(exclude_from_sim no)
		(in_bom yes)
		(on_board yes)
		(dnp no)
		(fields_autoplaced yes)
		(property "Reference" "C401"
			(at 120.65 190.4935 90)
			(effects
				(font
					(size 1.27 1.27)
				)
				(justify right)
			)
		)
		(property "Value" "C_100n_100V_0805"
			(at 128.27 175.26 0)
			(effects
				(font
					(size 1.27 1.27)
					(thickness 0.15)
				)
				(justify left bottom)
				(hide yes)
			)
		)
		(property "Footprint" "antmicro-footprints:C_0805_2012Metric"
			(at 130.81 175.26 0)
			(effects
				(font
					(size 1.27 1.27)
					(thickness 0.15)
				)
				(justify left bottom)
				(hide yes)
			)
		)
		(property "Datasheet" "https://product.samsungsem.com/mlcc/CL21B104KCFNNN.do"
			(at 133.35 175.26 0)
			(effects
				(font
					(size 1.27 1.27)
					(thickness 0.15)
				)
				(justify left bottom)
				(hide yes)
			)
		)
		(property "Description" ""
			(at 118.11 195.58 0)
			(effects
				(font
					(size 1.27 1.27)
				)
				(hide yes)
			)
		)
		(property "Manufacturer" "Samsung Electro-Mechanics"
			(at 138.43 175.26 0)
			(effects
				(font
					(size 1.27 1.27)
					(thickness 0.15)
				)
				(justify left bottom)
				(hide yes)
			)
		)
		(property "MPN" "CL21B104KCFNNNE"
			(at 135.89 175.26 0)
			(effects
				(font
					(size 1.27 1.27)
					(thickness 0.15)
				)
				(justify left bottom)
				(hide yes)
			)
		)
		(property "Val" "100n"
			(at 120.65 193.0335 90)
			(effects
				(font
					(size 1.27 1.27)
					(thickness 0.15)
				)
				(justify right)
			)
		)
		(property "License" "Apache-2.0"
			(at 140.97 175.26 0)
			(effects
				(font
					(size 1.27 1.27)
					(thickness 0.15)
				)
				(justify left bottom)
				(hide yes)
			)
		)
		(property "Author" "Antmicro"
			(at 143.51 175.26 0)
			(effects
				(font
					(size 1.27 1.27)
					(thickness 0.15)
				)
				(justify left bottom)
				(hide yes)
			)
		)
		(property "Voltage" "100V"
			(at 120.65 195.5735 90)
			(effects
				(font
					(size 1.27 1.27)
				)
				(justify right)
			)
		)
		(property "Dielectric" "X7R"
			(at 148.59 175.26 0)
			(effects
				(font
					(size 1.27 1.27)
				)
				(justify left bottom)
				(hide yes)
			)
		)
		(property "Public" "False"
			(at 151.13 175.26 0)
			(effects
				(font
					(size 1.27 1.27)
				)
				(justify left bottom)
				(hide yes)
			)
		)
		(pin "1"
		)
		(pin "2"
		)
		(instances
			(project "cm4-baseboard"
				(path ""
					(reference "C401")
					(unit 1)
				)
			)
		)
	)
	(symbol
		(lib_id "antmicroPMICPowerDistributionSwitchesLoadDrivers:TPS2372-3RGWR")
		(at 154.94 193.04 0)
		(unit 1)
		(exclude_from_sim no)
		(in_bom yes)
		(on_board yes)
		(dnp no)
		(property "Reference" "U401"
			(at 165.735 185.42 0)
			(effects
				(font
					(size 1.27 1.27)
				)
			)
		)
		(property "Value" "TPS2372-3RGWR"
			(at 165.735 187.96 0)
			(effects
				(font
					(size 1.27 1.27)
					(thickness 0.15)
				)
				(hide yes)
			)
		)
		(property "Footprint" "antmicro-footprints:VQFN-20_5x5x1mm_P0.65mm"
			(at 190.5 198.12 0)
			(effects
				(font
					(size 1.27 1.27)
					(thickness 0.15)
				)
				(justify left bottom)
				(hide yes)
			)
		)
		(property "Datasheet" "https://www.ti.com/lit/ds/symlink/tps2372.pdf?ts=1679042478513&ref_url=https%253A%252F%252Fwww.google.com%252F"
			(at 190.5 200.66 0)
			(effects
				(font
					(size 1.27 1.27)
					(thickness 0.15)
				)
				(justify left bottom)
				(hide yes)
			)
		)
		(property "Description" ""
			(at 154.94 193.04 0)
			(effects
				(font
					(size 1.27 1.27)
				)
				(hide yes)
			)
		)
		(property "MPN" "TPS2372-3RGWR"
			(at 157.48 189.23 0)
			(effects
				(font
					(size 1.27 1.27)
					(thickness 0.15)
				)
				(justify left bottom)
			)
		)
		(property "Manufacturer" "Texas Instruments"
			(at 190.5 205.74 0)
			(effects
				(font
					(size 1.27 1.27)
					(thickness 0.15)
				)
				(justify left bottom)
				(hide yes)
			)
		)
		(property "Author" "Antmicro"
			(at 190.5 208.28 0)
			(effects
				(font
					(size 1.27 1.27)
					(thickness 0.15)
				)
				(justify left bottom)
				(hide yes)
			)
		)
		(property "License" "Apache-2.0"
			(at 190.5 210.82 0)
			(effects
				(font
					(size 1.27 1.27)
					(thickness 0.15)
				)
				(justify left bottom)
				(hide yes)
			)
		)
		(pin "1"
		)
		(pin "10"
		)
		(pin "11"
		)
		(pin "12"
		)
		(pin "13"
		)
		(pin "14"
		)
		(pin "15"
		)
		(pin "16"
		)
		(pin "17"
		)
		(pin "18"
		)
		(pin "19"
		)
		(pin "2"
		)
		(pin "20"
		)
		(pin "21"
		)
		(pin "3"
		)
		(pin "4"
		)
		(pin "5"
		)
		(pin "6"
		)
		(pin "7"
		)
		(pin "8"
		)
		(pin "9"
		)
		(instances
			(project "cm4-baseboard"
				(path ""
					(reference "U401")
					(unit 1)
				)
			)
		)
	)
)
